(lib_symbols
	(symbol "antmicroCapacitors0402:C_100n_0402"
			(pin_numbers
				(hide yes)
			)
			(pin_names
				(hide yes)
			)
			(exclude_from_sim no)
			(in_bom yes)
			(on_board yes)
			(property "Reference" "C"
				(at 20.32 -5.08 0)
				(effects
					(font
						(size 1.27 1.27)
						(thickness 0.15)
					)
					(justify left bottom)
				)
			)
			(property "Value" "C_100n_0402"
				(at 20.32 -10.16 0)
				(effects
					(font
						(size 1.27 1.27)
						(thickness 0.15)
					)
					(justify left bottom)
					(hide yes)
				)
			)
			(property "Footprint" "antmicro-footprints:C_0402_1005Metric"
				(at 20.32 -12.7 0)
				(effects
					(font
						(size 1.27 1.27)
						(thickness 0.15)
					)
					(justify left bottom)
					(hide yes)
				)
			)
			(property "Datasheet" "https://www.murata.com/products/productdetail?partno=GRM155R61H104KE14%23"
				(at 20.32 -15.24 0)
				(effects
					(font
						(size 1.27 1.27)
						(thickness 0.15)
					)
					(justify left bottom)
					(hide yes)
				)
			)
			(property "Description" "SMD Multilayer Ceramic Capacitor, 0.1 µF, 50 V, 0402 [1005 Metric], ± 10%, X5R, GRM Series"
				(at 0 0 0)
				(effects
					(font
						(size 1.27 1.27)
					)
					(hide yes)
				)
			)
			(property "MPN" "GRM155R61H104KE14D"
				(at 20.32 -17.78 0)
				(effects
					(font
						(size 1.27 1.27)
						(thickness 0.15)
					)
					(justify left bottom)
					(hide yes)
				)
			)
			(property "Manufacturer" "Murata"
				(at 20.32 -20.32 0)
				(effects
					(font
						(size 1.27 1.27)
						(thickness 0.15)
					)
					(justify left bottom)
					(hide yes)
				)
			)
			(property "License" "Apache-2.0"
				(at 20.32 -22.86 0)
				(effects
					(font
						(size 1.27 1.27)
						(thickness 0.15)
					)
					(justify left bottom)
					(hide yes)
				)
			)
			(property "Author" "Antmicro"
				(at 20.32 -25.4 0)
				(effects
					(font
						(size 1.27 1.27)
						(thickness 0.15)
					)
					(justify left bottom)
					(hide yes)
				)
			)
			(property "Val" "100n"
				(at 20.32 -7.62 0)
				(effects
					(font
						(size 1.27 1.27)
						(thickness 0.15)
					)
					(justify left bottom)
				)
			)
			(property "Voltage" "50V"
				(at 20.32 -27.94 0)
				(effects
					(font
						(size 1.27 1.27)
					)
					(justify left bottom)
					(hide yes)
				)
			)
			(property "Dielectric" "X5R"
				(at 20.32 -30.48 0)
				(effects
					(font
						(size 1.27 1.27)
					)
					(justify left bottom)
					(hide yes)
				)
			)
			(property "ki_keywords" "0402, SMT, CAPACITOR, PASSIVE, CERAMIC, MLCC"
				(at 0 0 0)
				(effects
					(font
						(size 1.27 1.27)
					)
					(hide yes)
				)
			)
			(symbol "C_100n_0402_0_1"
				(polyline
					(pts
						(xy 2.032 -1.524) (xy 2.032 1.524)
					)
					(stroke
						(width 0.3048)
						(type default)
					)
					(fill
						(type none)
					)
				)
				(polyline
					(pts
						(xy 3.048 -1.524) (xy 3.048 1.524)
					)
					(stroke
						(width 0.3302)
						(type default)
					)
					(fill
						(type none)
					)
				)
			)
			(symbol "C_100n_0402_1_1"
				(pin passive line
					(at 0 0 0)
					(length 2.032)
					(name "~"
						(effects
							(font
								(size 1.27 1.27)
							)
						)
					)
					(number "1"
						(effects
							(font
								(size 1.27 1.27)
							)
						)
					)
				)
				(pin passive line
					(at 5.08 0 180)
					(length 2.032)
					(name "~"
						(effects
							(font
								(size 1.27 1.27)
							)
						)
					)
					(number "2"
						(effects
							(font
								(size 1.27 1.27)
							)
						)
					)
				)
			)
		)
	(symbol "antmicroCapacitors0402:C_10n_0402"
			(pin_numbers
				(hide yes)
			)
			(pin_names
				(hide yes)
			)
			(exclude_from_sim no)
			(in_bom yes)
			(on_board yes)
			(property "Reference" "C"
				(at 20.32 -5.08 0)
				(effects
					(font
						(size 1.27 1.27)
						(thickness 0.15)
					)
					(justify left bottom)
				)
			)
			(property "Value" "C_10n_0402"
				(at 20.32 -10.16 0)
				(effects
					(font
						(size 1.27 1.27)
						(thickness 0.15)
					)
					(justify left bottom)
					(hide yes)
				)
			)
			(property "Footprint" "antmicro-footprints:C_0402_1005Metric"
				(at 20.32 -12.7 0)
				(effects
					(font
						(size 1.27 1.27)
						(thickness 0.15)
					)
					(justify left bottom)
					(hide yes)
				)
			)
			(property "Datasheet" "https://www.murata.com/products/productdetail?partno=GRM155R71H103KA88%23"
				(at 20.32 -15.24 0)
				(effects
					(font
						(size 1.27 1.27)
						(thickness 0.15)
					)
					(justify left bottom)
					(hide yes)
				)
			)
			(property "Description" "SMD Multilayer Ceramic Capacitor, 10000 pF, 50 V, 0402 [1005 Metric], ± 10%, X7R, GRM Series"
				(at 0 0 0)
				(effects
					(font
						(size 1.27 1.27)
					)
					(hide yes)
				)
			)
			(property "MPN" "GRM155R71H103KA88D"
				(at 20.32 -17.78 0)
				(effects
					(font
						(size 1.27 1.27)
						(thickness 0.15)
					)
					(justify left bottom)
					(hide yes)
				)
			)
			(property "Manufacturer" "Murata"
				(at 20.32 -20.32 0)
				(effects
					(font
						(size 1.27 1.27)
						(thickness 0.15)
					)
					(justify left bottom)
					(hide yes)
				)
			)
			(property "License" "Apache-2.0"
				(at 20.32 -22.86 0)
				(effects
					(font
						(size 1.27 1.27)
						(thickness 0.15)
					)
					(justify left bottom)
					(hide yes)
				)
			)
			(property "Author" "Antmicro"
				(at 20.32 -25.4 0)
				(effects
					(font
						(size 1.27 1.27)
						(thickness 0.15)
					)
					(justify left bottom)
					(hide yes)
				)
			)
			(property "Val" "10n"
				(at 20.32 -7.62 0)
				(effects
					(font
						(size 1.27 1.27)
						(thickness 0.15)
					)
					(justify left bottom)
				)
			)
			(property "Voltage" "50V"
				(at 20.32 -27.94 0)
				(effects
					(font
						(size 1.27 1.27)
					)
					(justify left bottom)
					(hide yes)
				)
			)
			(property "Dielectric" "X7R"
				(at 20.32 -30.48 0)
				(effects
					(font
						(size 1.27 1.27)
					)
					(justify left bottom)
					(hide yes)
				)
			)
			(property "ki_keywords" "0402, SMT, CAPACITOR, PASSIVE"
				(at 0 0 0)
				(effects
					(font
						(size 1.27 1.27)
					)
					(hide yes)
				)
			)
			(symbol "C_10n_0402_0_1"
				(polyline
					(pts
						(xy 2.032 -1.524) (xy 2.032 1.524)
					)
					(stroke
						(width 0.3048)
						(type default)
					)
					(fill
						(type none)
					)
				)
				(polyline
					(pts
						(xy 3.048 -1.524) (xy 3.048 1.524)
					)
					(stroke
						(width 0.3302)
						(type default)
					)
					(fill
						(type none)
					)
				)
			)
			(symbol "C_10n_0402_1_1"
				(pin passive line
					(at 0 0 0)
					(length 2.032)
					(name "~"
						(effects
							(font
								(size 1.27 1.27)
							)
						)
					)
					(number "1"
						(effects
							(font
								(size 1.27 1.27)
							)
						)
					)
				)
				(pin passive line
					(at 5.08 0 180)
					(length 2.032)
					(name "~"
						(effects
							(font
								(size 1.27 1.27)
							)
						)
					)
					(number "2"
						(effects
							(font
								(size 1.27 1.27)
							)
						)
					)
				)
			)
		)
	(symbol "antmicroCapacitors0402:C_10u_0402"
			(pin_numbers
				(hide yes)
			)
			(pin_names
				(hide yes)
			)
			(exclude_from_sim no)
			(in_bom yes)
			(on_board yes)
			(property "Reference" "C"
				(at 20.32 -5.08 0)
				(effects
					(font
						(size 1.27 1.27)
						(thickness 0.15)
					)
					(justify left bottom)
				)
			)
			(property "Value" "C_10u_0402"
				(at 20.32 -10.16 0)
				(effects
					(font
						(size 1.27 1.27)
						(thickness 0.15)
					)
					(justify left bottom)
					(hide yes)
				)
			)
			(property "Footprint" "antmicro-footprints:C_0402_1005Metric"
				(at 20.32 -12.7 0)
				(effects
					(font
						(size 1.27 1.27)
						(thickness 0.15)
					)
					(justify left bottom)
					(hide yes)
				)
			)
			(property "Datasheet" "https://www.yageo.com/en/Chart/Download/pdf/CC0402MRX5R5BB106"
				(at 20.32 -15.24 0)
				(effects
					(font
						(size 1.27 1.27)
						(thickness 0.15)
					)
					(justify left bottom)
					(hide yes)
				)
			)
			(property "Description" "SMD Multilayer Ceramic Capacitor, 10 µF, 6.3 V, 0402 [1005 Metric], ± 20%, X5R, CC Series"
				(at 0 0 0)
				(effects
					(font
						(size 1.27 1.27)
					)
					(hide yes)
				)
			)
			(property "MPN" "CC0402MRX5R5BB106"
				(at 20.32 -17.78 0)
				(effects
					(font
						(size 1.27 1.27)
						(thickness 0.15)
					)
					(justify left bottom)
					(hide yes)
				)
			)
			(property "Manufacturer" "YAGEO"
				(at 20.32 -20.32 0)
				(effects
					(font
						(size 1.27 1.27)
						(thickness 0.15)
					)
					(justify left bottom)
					(hide yes)
				)
			)
			(property "License" "Apache-2.0"
				(at 20.32 -22.86 0)
				(effects
					(font
						(size 1.27 1.27)
						(thickness 0.15)
					)
					(justify left bottom)
					(hide yes)
				)
			)
			(property "Author" "Antmicro"
				(at 20.32 -25.4 0)
				(effects
					(font
						(size 1.27 1.27)
						(thickness 0.15)
					)
					(justify left bottom)
					(hide yes)
				)
			)
			(property "Val" "10u"
				(at 20.32 -7.62 0)
				(effects
					(font
						(size 1.27 1.27)
						(thickness 0.15)
					)
					(justify left bottom)
				)
			)
			(property "Voltage" ""
				(at 20.32 -27.94 0)
				(effects
					(font
						(size 1.27 1.27)
					)
					(justify left bottom)
					(hide yes)
				)
			)
			(property "Dielectric" ""
				(at 20.32 -30.48 0)
				(effects
					(font
						(size 1.27 1.27)
					)
					(justify left bottom)
					(hide yes)
				)
			)
			(property "ki_keywords" "0402, SMT, CAPACITOR, PASSIVE, MLCC, CERAMIC"
				(at 0 0 0)
				(effects
					(font
						(size 1.27 1.27)
					)
					(hide yes)
				)
			)
			(symbol "C_10u_0402_0_1"
				(polyline
					(pts
						(xy 2.032 -1.524) (xy 2.032 1.524)
					)
					(stroke
						(width 0.3048)
						(type default)
					)
					(fill
						(type none)
					)
				)
				(polyline
					(pts
						(xy 3.048 -1.524) (xy 3.048 1.524)
					)
					(stroke
						(width 0.3302)
						(type default)
					)
					(fill
						(type none)
					)
				)
			)
			(symbol "C_10u_0402_1_1"
				(pin passive line
					(at 0 0 0)
					(length 2.032)
					(name "~"
						(effects
							(font
								(size 1.27 1.27)
							)
						)
					)
					(number "1"
						(effects
							(font
								(size 1.27 1.27)
							)
						)
					)
				)
				(pin passive line
					(at 5.08 0 180)
					(length 2.032)
					(name "~"
						(effects
							(font
								(size 1.27 1.27)
							)
						)
					)
					(number "2"
						(effects
							(font
								(size 1.27 1.27)
							)
						)
					)
				)
			)
		)
	(symbol "antmicroCapacitors0402:C_1u_0402"
			(pin_numbers
				(hide yes)
			)
			(pin_names
				(hide yes)
			)
			(exclude_from_sim no)
			(in_bom yes)
			(on_board yes)
			(property "Reference" "C"
				(at 20.32 -5.08 0)
				(effects
					(font
						(size 1.27 1.27)
						(thickness 0.15)
					)
					(justify left bottom)
				)
			)
			(property "Value" "C_1u_0402"
				(at 20.32 -10.16 0)
				(effects
					(font
						(size 1.27 1.27)
						(thickness 0.15)
					)
					(justify left bottom)
					(hide yes)
				)
			)
			(property "Footprint" "antmicro-footprints:C_0402_1005Metric"
				(at 20.32 -12.7 0)
				(effects
					(font
						(size 1.27 1.27)
						(thickness 0.15)
					)
					(justify left bottom)
					(hide yes)
				)
			)
			(property "Datasheet" "https://product.tdk.com/en/search/capacitor/ceramic/mlcc/info?part_no=C1005X6S1A105K050BC"
				(at 20.32 -15.24 0)
				(effects
					(font
						(size 1.27 1.27)
						(thickness 0.15)
					)
					(justify left bottom)
					(hide yes)
				)
			)
			(property "Description" "SMD Multilayer Ceramic Capacitor, 1 µF, 10 V, 0402 [1005 Metric], ± 10%, X6S, C"
				(at 0 0 0)
				(effects
					(font
						(size 1.27 1.27)
					)
					(hide yes)
				)
			)
			(property "MPN" "C1005X6S1A105K050BC"
				(at 20.32 -17.78 0)
				(effects
					(font
						(size 1.27 1.27)
						(thickness 0.15)
					)
					(justify left bottom)
					(hide yes)
				)
			)
			(property "Manufacturer" "TDK"
				(at 20.32 -20.32 0)
				(effects
					(font
						(size 1.27 1.27)
						(thickness 0.15)
					)
					(justify left bottom)
					(hide yes)
				)
			)
			(property "License" "Apache-2.0"
				(at 20.32 -22.86 0)
				(effects
					(font
						(size 1.27 1.27)
						(thickness 0.15)
					)
					(justify left bottom)
					(hide yes)
				)
			)
			(property "Author" "Antmicro"
				(at 20.32 -25.4 0)
				(effects
					(font
						(size 1.27 1.27)
						(thickness 0.15)
					)
					(justify left bottom)
					(hide yes)
				)
			)
			(property "Val" "1u"
				(at 20.32 -7.62 0)
				(effects
					(font
						(size 1.27 1.27)
						(thickness 0.15)
					)
					(justify left bottom)
				)
			)
			(property "Voltage" ""
				(at 20.32 -27.94 0)
				(effects
					(font
						(size 1.27 1.27)
					)
					(justify left bottom)
					(hide yes)
				)
			)
			(property "Dielectric" ""
				(at 20.32 -30.48 0)
				(effects
					(font
						(size 1.27 1.27)
					)
					(justify left bottom)
					(hide yes)
				)
			)
			(property "ki_keywords" "0402, SMT, CAPACITOR, PASSIVE, CERAMIC, MLCC"
				(at 0 0 0)
				(effects
					(font
						(size 1.27 1.27)
					)
					(hide yes)
				)
			)
			(symbol "C_1u_0402_0_1"
				(polyline
					(pts
						(xy 2.032 -1.524) (xy 2.032 1.524)
					)
					(stroke
						(width 0.3048)
						(type default)
					)
					(fill
						(type none)
					)
				)
				(polyline
					(pts
						(xy 3.048 -1.524) (xy 3.048 1.524)
					)
					(stroke
						(width 0.3302)
						(type default)
					)
					(fill
						(type none)
					)
				)
			)
			(symbol "C_1u_0402_1_1"
				(pin passive line
					(at 0 0 0)
					(length 2.032)
					(name "~"
						(effects
							(font
								(size 1.27 1.27)
							)
						)
					)
					(number "1"
						(effects
							(font
								(size 1.27 1.27)
							)
						)
					)
				)
				(pin passive line
					(at 5.08 0 180)
					(length 2.032)
					(name "~"
						(effects
							(font
								(size 1.27 1.27)
							)
						)
					)
					(number "2"
						(effects
							(font
								(size 1.27 1.27)
							)
						)
					)
				)
			)
		)
	(symbol "antmicroCapacitors0402:C_220p_0402"
			(pin_numbers
				(hide yes)
			)
			(pin_names
				(hide yes)
			)
			(exclude_from_sim no)
			(in_bom yes)
			(on_board yes)
			(property "Reference" "C"
				(at 20.32 -5.08 0)
				(effects
					(font
						(size 1.27 1.27)
						(thickness 0.15)
					)
					(justify left bottom)
				)
			)
			(property "Value" "C_220p_0402"
				(at 20.32 -10.16 0)
				(effects
					(font
						(size 1.27 1.27)
						(thickness 0.15)
					)
					(justify left bottom)
					(hide yes)
				)
			)
			(property "Footprint" "antmicro-footprints:C_0402_1005Metric"
				(at 20.32 -12.7 0)
				(effects
					(font
						(size 1.27 1.27)
						(thickness 0.15)
					)
					(justify left bottom)
					(hide yes)
				)
			)
			(property "Datasheet" "https://spicat.kyocera-avx.com/product/mlcc/chartview/04025C221JAT2A/"
				(at 20.32 -15.24 0)
				(effects
					(font
						(size 1.27 1.27)
						(thickness 0.15)
					)
					(justify left bottom)
					(hide yes)
				)
			)
			(property "Description" "SMD Multilayer Ceramic Capacitor, 220 pF, 50 V, 0402 [1005 Metric], ± 10%, X7R, MC"
				(at 0 0 0)
				(effects
					(font
						(size 1.27 1.27)
					)
					(hide yes)
				)
			)
			(property "MPN" "04025C221JAT2A"
				(at 20.32 -17.78 0)
				(effects
					(font
						(size 1.27 1.27)
						(thickness 0.15)
					)
					(justify left bottom)
					(hide yes)
				)
			)
			(property "Manufacturer" "KYOCERA AVX"
				(at 20.32 -20.32 0)
				(effects
					(font
						(size 1.27 1.27)
						(thickness 0.15)
					)
					(justify left bottom)
					(hide yes)
				)
			)
			(property "License" "Apache-2.0"
				(at 20.32 -22.86 0)
				(effects
					(font
						(size 1.27 1.27)
						(thickness 0.15)
					)
					(justify left bottom)
					(hide yes)
				)
			)
			(property "Author" "Antmicro"
				(at 20.32 -25.4 0)
				(effects
					(font
						(size 1.27 1.27)
						(thickness 0.15)
					)
					(justify left bottom)
					(hide yes)
				)
			)
			(property "Val" "220p"
				(at 20.32 -7.62 0)
				(effects
					(font
						(size 1.27 1.27)
						(thickness 0.15)
					)
					(justify left bottom)
				)
			)
			(property "Voltage" ""
				(at 20.32 -27.94 0)
				(effects
					(font
						(size 1.27 1.27)
					)
					(justify left bottom)
					(hide yes)
				)
			)
			(property "Dielectric" ""
				(at 20.32 -30.48 0)
				(effects
					(font
						(size 1.27 1.27)
					)
					(justify left bottom)
					(hide yes)
				)
			)
			(property "ki_keywords" "0402, SMT, CAPACITOR, PASSIVE"
				(at 0 0 0)
				(effects
					(font
						(size 1.27 1.27)
					)
					(hide yes)
				)
			)
			(symbol "C_220p_0402_0_1"
				(polyline
					(pts
						(xy 2.032 -1.524) (xy 2.032 1.524)
					)
					(stroke
						(width 0.3048)
						(type default)
					)
					(fill
						(type none)
					)
				)
				(polyline
					(pts
						(xy 3.048 -1.524) (xy 3.048 1.524)
					)
					(stroke
						(width 0.3302)
						(type default)
					)
					(fill
						(type none)
					)
				)
			)
			(symbol "C_220p_0402_1_1"
				(pin passive line
					(at 0 0 0)
					(length 2.032)
					(name "~"
						(effects
							(font
								(size 1.27 1.27)
							)
						)
					)
					(number "1"
						(effects
							(font
								(size 1.27 1.27)
							)
						)
					)
				)
				(pin passive line
					(at 5.08 0 180)
					(length 2.032)
					(name "~"
						(effects
							(font
								(size 1.27 1.27)
							)
						)
					)
					(number "2"
						(effects
							(font
								(size 1.27 1.27)
							)
						)
					)
				)
			)
		)
	(symbol "antmicroCapacitors0402:C_22u_0402"
			(pin_numbers
				(hide yes)
			)
			(pin_names
				(hide yes)
			)
			(exclude_from_sim no)
			(in_bom yes)
			(on_board yes)
			(property "Reference" "C"
				(at 20.32 -5.08 0)
				(effects
					(font
						(size 1.27 1.27)
						(thickness 0.15)
					)
					(justify left bottom)
				)
			)
			(property "Value" "C_22u_0402"
				(at 20.32 -10.16 0)
				(effects
					(font
						(size 1.27 1.27)
						(thickness 0.15)
					)
					(justify left bottom)
					(hide yes)
				)
			)
			(property "Footprint" "antmicro-footprints:C_0402_1005Metric"
				(at 20.32 -12.7 0)
				(effects
					(font
						(size 1.27 1.27)
						(thickness 0.15)
					)
					(justify left bottom)
					(hide yes)
				)
			)
			(property "Datasheet" "https://www.murata.com/products/productdetail?partno=GRM158R60J226ME01%23"
				(at 20.32 -15.24 0)
				(effects
					(font
						(size 1.27 1.27)
						(thickness 0.15)
					)
					(justify left bottom)
					(hide yes)
				)
			)
			(property "Description" "SMD Multilayer Ceramic Capacitor, 22 uF, 4 V, 0402 [1005 Metric], X6S"
				(at 0 0 0)
				(effects
					(font
						(size 1.27 1.27)
					)
					(hide yes)
				)
			)
			(property "MPN" "GRM158R60J226ME01D"
				(at 20.32 -17.78 0)
				(effects
					(font
						(size 1.27 1.27)
						(thickness 0.15)
					)
					(justify left bottom)
					(hide yes)
				)
			)
			(property "Manufacturer" "Murata"
				(at 20.32 -20.32 0)
				(effects
					(font
						(size 1.27 1.27)
						(thickness 0.15)
					)
					(justify left bottom)
					(hide yes)
				)
			)
			(property "License" "Apache-2.0"
				(at 20.32 -22.86 0)
				(effects
					(font
						(size 1.27 1.27)
						(thickness 0.15)
					)
					(justify left bottom)
					(hide yes)
				)
			)
			(property "Author" "Antmicro"
				(at 20.32 -25.4 0)
				(effects
					(font
						(size 1.27 1.27)
						(thickness 0.15)
					)
					(justify left bottom)
					(hide yes)
				)
			)
			(property "Val" "22u"
				(at 20.32 -7.62 0)
				(effects
					(font
						(size 1.27 1.27)
						(thickness 0.15)
					)
					(justify left bottom)
				)
			)
			(property "Voltage" ""
				(at 20.32 -27.94 0)
				(effects
					(font
						(size 1.27 1.27)
					)
					(justify left bottom)
					(hide yes)
				)
			)
			(property "Dielectric" ""
				(at 20.32 -30.48 0)
				(effects
					(font
						(size 1.27 1.27)
					)
					(justify left bottom)
					(hide yes)
				)
			)
			(property "ki_keywords" "1210, SMT, CAPACITOR, PASSIVE, CERAMIC, MLCC"
				(at 0 0 0)
				(effects
					(font
						(size 1.27 1.27)
					)
					(hide yes)
				)
			)
			(symbol "C_22u_0402_0_1"
				(polyline
					(pts
						(xy 2.032 -1.524) (xy 2.032 1.524)
					)
					(stroke
						(width 0.3048)
						(type default)
					)
					(fill
						(type none)
					)
				)
				(polyline
					(pts
						(xy 3.048 -1.524) (xy 3.048 1.524)
					)
					(stroke
						(width 0.3302)
						(type default)
					)
					(fill
						(type none)
					)
				)
			)
			(symbol "C_22u_0402_1_1"
				(pin passive line
					(at 0 0 0)
					(length 2.032)
					(name "~"
						(effects
							(font
								(size 1.27 1.27)
							)
						)
					)
					(number "1"
						(effects
							(font
								(size 1.27 1.27)
							)
						)
					)
				)
				(pin passive line
					(at 5.08 0 180)
					(length 2.032)
					(name "~"
						(effects
							(font
								(size 1.27 1.27)
							)
						)
					)
					(number "2"
						(effects
							(font
								(size 1.27 1.27)
							)
						)
					)
				)
			)
		)
	(symbol "antmicroCapacitors0402:C_2u2_0402"
			(pin_numbers
				(hide yes)
			)
			(pin_names
				(hide yes)
			)
			(exclude_from_sim no)
			(in_bom yes)
			(on_board yes)
			(property "Reference" "C"
				(at 20.32 -5.08 0)
				(effects
					(font
						(size 1.27 1.27)
						(thickness 0.15)
					)
					(justify left bottom)
				)
			)
			(property "Value" "C_2u2_0402"
				(at 20.32 -10.16 0)
				(effects
					(font
						(size 1.27 1.27)
						(thickness 0.15)
					)
					(justify left bottom)
					(hide yes)
				)
			)
			(property "Footprint" "antmicro-footprints:C_0402_1005Metric"
				(at 20.32 -12.7 0)
				(effects
					(font
						(size 1.27 1.27)
						(thickness 0.15)
					)
					(justify left bottom)
					(hide yes)
				)
			)
			(property "Datasheet" "https://product.tdk.com/en/search/capacitor/ceramic/mlcc/info?part_no=C1005X5R1A225K050BC"
				(at 20.32 -15.24 0)
				(effects
					(font
						(size 1.27 1.27)
						(thickness 0.15)
					)
					(justify left bottom)
					(hide yes)
				)
			)
			(property "Description" "SMD Multilayer Ceramic Capacitor, 2.2 µF, 10 V, 0402 [1005 Metric], ± 10%, X5R, C"
				(at 0 0 0)
				(effects
					(font
						(size 1.27 1.27)
					)
					(hide yes)
				)
			)
			(property "MPN" "C1005X5R1A225K050BC"
				(at 20.32 -17.78 0)
				(effects
					(font
						(size 1.27 1.27)
						(thickness 0.15)
					)
					(justify left bottom)
					(hide yes)
				)
			)
			(property "Manufacturer" "TDK"
				(at 20.32 -20.32 0)
				(effects
					(font
						(size 1.27 1.27)
						(thickness 0.15)
					)
					(justify left bottom)
					(hide yes)
				)
			)
			(property "License" "Apache-2.0"
				(at 20.32 -22.86 0)
				(effects
					(font
						(size 1.27 1.27)
						(thickness 0.15)
					)
					(justify left bottom)
					(hide yes)
				)
			)
			(property "Author" "Antmicro"
				(at 20.32 -25.4 0)
				(effects
					(font
						(size 1.27 1.27)
						(thickness 0.15)
					)
					(justify left bottom)
					(hide yes)
				)
			)
			(property "Val" "2u2"
				(at 20.32 -7.62 0)
				(effects
					(font
						(size 1.27 1.27)
						(thickness 0.15)
					)
					(justify left bottom)
				)
			)
			(property "Voltage" ""
				(at 20.32 -27.94 0)
				(effects
					(font
						(size 1.27 1.27)
					)
					(justify left bottom)
					(hide yes)
				)
			)
			(property "Dielectric" ""
				(at 20.32 -30.48 0)
				(effects
					(font
						(size 1.27 1.27)
					)
					(justify left bottom)
					(hide yes)
				)
			)
			(property "ki_keywords" "0402, SMT, CAPACITOR, PASSIVE, CERAMIC, MLCC"
				(at 0 0 0)
				(effects
					(font
						(size 1.27 1.27)
					)
					(hide yes)
				)
			)
			(symbol "C_2u2_0402_0_1"
				(polyline
					(pts
						(xy 2.032 -1.524) (xy 2.032 1.524)
					)
					(stroke
						(width 0.3048)
						(type default)
					)
					(fill
						(type none)
					)
				)
				(polyline
					(pts
						(xy 3.048 -1.524) (xy 3.048 1.524)
					)
					(stroke
						(width 0.3302)
						(type default)
					)
					(fill
						(type none)
					)
				)
			)
			(symbol "C_2u2_0402_1_1"
				(pin passive line
					(at 0 0 0)
					(length 2.032)
					(name "~"
						(effects
							(font
								(size 1.27 1.27)
							)
						)
					)
					(number "1"
						(effects
							(font
								(size 1.27 1.27)
							)
						)
					)
				)
				(pin passive line
					(at 5.08 0 180)
					(length 2.032)
					(name "~"
						(effects
							(font
								(size 1.27 1.27)
							)
						)
					)
					(number "2"
						(effects
							(font
								(size 1.27 1.27)
							)
						)
					)
				)
			)
		)
	(symbol "antmicroCapacitors0402:C_33p_0402"
			(pin_numbers
				(hide yes)
			)
			(pin_names
				(hide yes)
			)
			(exclude_from_sim no)
			(in_bom yes)
			(on_board yes)
			(property "Reference" "C"
				(at 20.32 -5.08 0)
				(effects
					(font
						(size 1.27 1.27)
						(thickness 0.15)
					)
					(justify left bottom)
				)
			)
			(property "Value" "C_33p_0402"
				(at 20.32 -10.16 0)
				(effects
					(font
						(size 1.27 1.27)
						(thickness 0.15)
					)
					(justify left bottom)
					(hide yes)
				)
			)
			(property "Footprint" "antmicro-footprints:C_0402_1005Metric"
				(at 20.32 -12.7 0)
				(effects
					(font
						(size 1.27 1.27)
						(thickness 0.15)
					)
					(justify left bottom)
					(hide yes)
				)
			)
			(property "Datasheet" "https://spicat.kyocera-avx.com/product/mlcc/chartview/04025A330FAT2A/"
				(at 20.32 -15.24 0)
				(effects
					(font
						(size 1.27 1.27)
						(thickness 0.15)
					)
					(justify left bottom)
					(hide yes)
				)
			)
			(property "Description" "SMD Multilayer Ceramic Capacitor, 33 pF, 50 V, 0402 [1005 Metric], ± 5%, C0G / NP0, MC"
				(at 0 0 0)
				(effects
					(font
						(size 1.27 1.27)
					)
					(hide yes)
				)
			)
			(property "MPN" "04025A330FAT2A"
				(at 20.32 -17.78 0)
				(effects
					(font
						(size 1.27 1.27)
						(thickness 0.15)
					)
					(justify left bottom)
					(hide yes)
				)
			)
			(property "Manufacturer" "KYOCERA AVX"
				(at 20.32 -20.32 0)
				(effects
					(font
						(size 1.27 1.27)
						(thickness 0.15)
					)
					(justify left bottom)
					(hide yes)
				)
			)
			(property "License" "Apache-2.0"
				(at 20.32 -22.86 0)
				(effects
					(font
						(size 1.27 1.27)
						(thickness 0.15)
					)
					(justify left bottom)
					(hide yes)
				)
			)
			(property "Author" "Antmicro"
				(at 20.32 -25.4 0)
				(effects
					(font
						(size 1.27 1.27)
						(thickness 0.15)
					)
					(justify left bottom)
					(hide yes)
				)
			)
			(property "Val" "33p"
				(at 20.32 -7.62 0)
				(effects
					(font
						(size 1.27 1.27)
						(thickness 0.15)
					)
					(justify left bottom)
				)
			)
			(property "Voltage" ""
				(at 20.32 -27.94 0)
				(effects
					(font
						(size 1.27 1.27)
					)
					(justify left bottom)
					(hide yes)
				)
			)
			(property "Dielectric" ""
				(at 20.32 -30.48 0)
				(effects
					(font
						(size 1.27 1.27)
					)
					(justify left bottom)
					(hide yes)
				)
			)
			(property "ki_keywords" "0402, SMT, CAPACITOR, PASSIVE"
				(at 0 0 0)
				(effects
					(font
						(size 1.27 1.27)
					)
					(hide yes)
				)
			)
			(symbol "C_33p_0402_0_1"
				(polyline
					(pts
						(xy 2.032 -1.524) (xy 2.032 1.524)
					)
					(stroke
						(width 0.3048)
						(type default)
					)
					(fill
						(type none)
					)
				)
				(polyline
					(pts
						(xy 3.048 -1.524) (xy 3.048 1.524)
					)
					(stroke
						(width 0.3302)
						(type default)
					)
					(fill
						(type none)
					)
				)
			)
			(symbol "C_33p_0402_1_1"
				(pin passive line
					(at 0 0 0)
					(length 2.032)
					(name "~"
						(effects
							(font
								(size 1.27 1.27)
							)
						)
					)
					(number "1"
						(effects
							(font
								(size 1.27 1.27)
							)
						)
					)
				)
				(pin passive line
					(at 5.08 0 180)
					(length 2.032)
					(name "~"
						(effects
							(font
								(size 1.27 1.27)
							)
						)
					)
					(number "2"
						(effects
							(font
								(size 1.27 1.27)
							)
						)
					)
				)
			)
		)
	(symbol "antmicroCapacitors0603:C_10u_25V_0603"
			(pin_numbers
				(hide yes)
			)
			(pin_names
				(hide yes)
			)
			(exclude_from_sim no)
			(in_bom yes)
			(on_board yes)
			(property "Reference" "C"
				(at 20.32 -5.08 0)
				(effects
					(font
						(size 1.27 1.27)
						(thickness 0.15)
					)
					(justify left bottom)
				)
			)
			(property "Value" "C_10u_25V_0603"
				(at 20.32 -10.16 0)
				(effects
					(font
						(size 1.27 1.27)
						(thickness 0.15)
					)
					(justify left bottom)
					(hide yes)
				)
			)
			(property "Footprint" "antmicro-footprints:C_0603_1608Metric"
				(at 20.32 -12.7 0)
				(effects
					(font
						(size 1.27 1.27)
						(thickness 0.15)
					)
					(justify left bottom)
					(hide yes)
				)
			)
			(property "Datasheet" "https://product.tdk.com/en/search/capacitor/ceramic/mlcc/info?part_no=C1608X5R1E106M080AC"
				(at 20.32 -15.24 0)
				(effects
					(font
						(size 1.27 1.27)
						(thickness 0.15)
					)
					(justify left bottom)
					(hide yes)
				)
			)
			(property "Description" "SMD Multilayer Ceramic Capacitor, 10 µF, 25 V, 0603 [1608 Metric], ± 20%, X5R, C"
				(at 0 0 0)
				(effects
					(font
						(size 1.27 1.27)
					)
					(hide yes)
				)
			)
			(property "MPN" "C1608X5R1E106M080AC"
				(at 20.32 -17.78 0)
				(effects
					(font
						(size 1.27 1.27)
						(thickness 0.15)
					)
					(justify left bottom)
					(hide yes)
				)
			)
			(property "Manufacturer" "TDK"
				(at 20.32 -20.32 0)
				(effects
					(font
						(size 1.27 1.27)
						(thickness 0.15)
					)
					(justify left bottom)
					(hide yes)
				)
			)
			(property "License" "Apache-2.0"
				(at 20.32 -22.86 0)
				(effects
					(font
						(size 1.27 1.27)
						(thickness 0.15)
					)
					(justify left bottom)
					(hide yes)
				)
			)
			(property "Author" "Antmicro"
				(at 20.32 -25.4 0)
				(effects
					(font
						(size 1.27 1.27)
						(thickness 0.15)
					)
					(justify left bottom)
					(hide yes)
				)
			)
			(property "Val" "10u"
				(at 20.32 -7.62 0)
				(effects
					(font
						(size 1.27 1.27)
						(thickness 0.15)
					)
					(justify left bottom)
				)
			)
			(property "Voltage" "25V"
				(at 20.32 -27.94 0)
				(effects
					(font
						(size 1.27 1.27)
					)
					(justify left bottom)
					(hide yes)
				)
			)
			(property "Dielectric" ""
				(at 20.32 -30.48 0)
				(effects
					(font
						(size 1.27 1.27)
					)
					(justify left bottom)
					(hide yes)
				)
			)
			(property "ki_keywords" "0603, SMT, CAPACITOR, PASSIVE, CERAMIC, MLCC"
				(at 0 0 0)
				(effects
					(font
						(size 1.27 1.27)
					)
					(hide yes)
				)
			)
			(symbol "C_10u_25V_0603_0_1"
				(polyline
					(pts
						(xy 2.032 -1.524) (xy 2.032 1.524)
					)
					(stroke
						(width 0.3048)
						(type default)
					)
					(fill
						(type none)
					)
				)
				(polyline
					(pts
						(xy 3.048 -1.524) (xy 3.048 1.524)
					)
					(stroke
						(width 0.3302)
						(type default)
					)
					(fill
						(type none)
					)
				)
			)
			(symbol "C_10u_25V_0603_1_1"
				(pin passive line
					(at 0 0 0)
					(length 2.032)
					(name "~"
						(effects
							(font
								(size 1.27 1.27)
							)
						)
					)
					(number "1"
						(effects
							(font
								(size 1.27 1.27)
							)
						)
					)
				)
				(pin passive line
					(at 5.08 0 180)
					(length 2.032)
					(name "~"
						(effects
							(font
								(size 1.27 1.27)
							)
						)
					)
					(number "2"
						(effects
							(font
								(size 1.27 1.27)
							)
						)
					)
				)
			)
		)
	(symbol "antmicroCoaxialConnectorsRF:Conn_FAKRA_7-2287906-0"
			(pin_names
				(hide yes)
			)
			(exclude_from_sim no)
			(in_bom yes)
			(on_board yes)
			(property "Reference" "J"
				(at 20.32 -5.08 0)
				(effects
					(font
						(size 1.27 1.27)
						(thickness 0.15)
					)
					(justify left bottom)
				)
			)
			(property "Value" "Conn_FAKRA_7-2287906-0"
				(at 20.32 -7.62 0)
				(effects
					(font
						(size 1.27 1.27)
						(thickness 0.15)
					)
					(justify left bottom)
					(hide yes)
				)
			)
			(property "Footprint" "antmicro-footprints:Conn_FAKRA_7-2287906-0"
				(at 20.32 -10.16 0)
				(effects
					(font
						(size 1.27 1.27)
						(thickness 0.15)
					)
					(justify left bottom)
					(hide yes)
				)
			)
			(property "Datasheet" "https://www.te.com/en/product-7-2287906-0.html"
				(at 20.32 -12.7 0)
				(effects
					(font
						(size 1.27 1.27)
						(thickness 0.15)
					)
					(justify left bottom)
					(hide yes)
				)
			)
			(property "Description" "FAKRA, 1 POS, ASSY EDGE MOUNT, 12OCLOCK"
				(at 0 0 0)
				(effects
					(font
						(size 1.27 1.27)
					)
					(hide yes)
				)
			)
			(property "MPN" "7-2287906-0"
				(at 20.32 -15.24 0)
				(effects
					(font
						(size 1.27 1.27)
						(thickness 0.15)
					)
					(justify left bottom)
				)
			)
			(property "Manufacturer" "TE Connectivity"
				(at 20.32 -17.78 0)
				(effects
					(font
						(size 1.27 1.27)
						(thickness 0.15)
					)
					(justify left bottom)
					(hide yes)
				)
			)
			(property "Author" "Antmicro"
				(at 20.32 -20.32 0)
				(effects
					(font
						(size 1.27 1.27)
						(thickness 0.15)
					)
					(justify left bottom)
					(hide yes)
				)
			)
			(property "License" "Apache-2.0"
				(at 20.32 -22.86 0)
				(effects
					(font
						(size 1.27 1.27)
						(thickness 0.15)
					)
					(justify left bottom)
					(hide yes)
				)
			)
			(property "ki_keywords" "CONNECTOR"
				(at 0 0 0)
				(effects
					(font
						(size 1.27 1.27)
					)
					(hide yes)
				)
			)
			(property "ki_fp_filters" "*BNC* *SMA* *SMB* *SMC* *Cinch*"
				(at 0 0 0)
				(effects
					(font
						(size 1.27 1.27)
					)
					(hide yes)
				)
			)
			(symbol "Conn_FAKRA_7-2287906-0_1_1"
				(polyline
					(pts
						(xy 2.54 0) (xy 4.572 0)
					)
					(stroke
						(width 0.254)
						(type default)
					)
					(fill
						(type none)
					)
				)
				(arc
					(start 3.302 0.508)
					(mid 5.302 1.8083)
					(end 6.858 0)
					(stroke
						(width 0.254)
						(type default)
					)
					(fill
						(type none)
					)
				)
				(arc
					(start 6.858 0)
					(mid 5.302 -1.808)
					(end 3.302 -0.508)
					(stroke
						(width 0.254)
						(type default)
					)
					(fill
						(type none)
					)
				)
				(circle
					(center 5.08 0)
					(radius 0.508)
					(stroke
						(width 0.254)
						(type default)
					)
					(fill
						(type none)
					)
				)
				(polyline
					(pts
						(xy 5.08 -2.54) (xy 5.08 -1.778)
					)
					(stroke
						(width 0.254)
						(type default)
					)
					(fill
						(type none)
					)
				)
				(pin passive line
					(at 0 0 0)
					(length 2.54)
					(name "1"
						(effects
							(font
								(size 1.27 1.27)
							)
						)
					)
					(number "1"
						(effects
							(font
								(size 1.27 1.27)
							)
						)
					)
				)
				(pin passive line
					(at 5.08 -5.08 90)
					(length 2.54)
					(name "2"
						(effects
							(font
								(size 1.27 1.27)
							)
						)
					)
					(number "2"
						(effects
							(font
								(size 1.27 1.27)
							)
						)
					)
				)
				(pin passive line
					(at 5.08 -5.08 90)
					(length 2.54)
					(hide yes)
					(name "3"
						(effects
							(font
								(size 1.27 1.27)
							)
						)
					)
					(number "3"
						(effects
							(font
								(size 1.27 1.27)
							)
						)
					)
				)
				(pin passive line
					(at 5.08 -5.08 90)
					(length 2.54)
					(hide yes)
					(name "4"
						(effects
							(font
								(size 1.27 1.27)
							)
						)
					)
					(number "4"
						(effects
							(font
								(size 1.27 1.27)
							)
						)
					)
				)
				(pin passive line
					(at 5.08 -5.08 90)
					(length 2.54)
					(hide yes)
					(name "5"
						(effects
							(font
								(size 1.27 1.27)
							)
						)
					)
					(number "5"
						(effects
							(font
								(size 1.27 1.27)
							)
						)
					)
				)
			)
		)
	(symbol "antmicroDCDCConverters:AP62301_TSOT"
			(exclude_from_sim no)
			(in_bom yes)
			(on_board yes)
			(property "Reference" "U"
				(at 35.56 -2.54 0)
				(effects
					(font
						(size 1.27 1.27)
						(thickness 0.15)
					)
					(justify left bottom)
				)
			)
			(property "Value" "AP62301_TSOT"
				(at 35.56 -7.62 0)
				(effects
					(font
						(size 1.27 1.27)
						(thickness 0.15)
					)
					(justify left bottom)
					(hide yes)
				)
			)
			(property "Footprint" "antmicro-footprints:TSOT23-6"
				(at 35.56 -10.16 0)
				(effects
					(font
						(size 1.27 1.27)
						(thickness 0.15)
					)
					(justify left bottom)
					(hide yes)
				)
			)
			(property "Datasheet" "https://www.diodes.com/assets/Datasheets/AP62300_AP62301_AP62300T.pdf"
				(at 35.56 -12.7 0)
				(effects
					(font
						(size 1.27 1.27)
						(thickness 0.15)
					)
					(justify left bottom)
					(hide yes)
				)
			)
			(property "Description" "DC-DC Switching Synchronous Buck Regulator, Adjustable, 4.2V-18Vin, 0.8V-7V/3A out, TSOT-26-6"
				(at 0 0 0)
				(effects
					(font
						(size 1.27 1.27)
					)
					(hide yes)
				)
			)
			(property "MPN" "AP62301WU-7"
				(at 35.56 -5.08 0)
				(effects
					(font
						(size 1.27 1.27)
						(thickness 0.15)
					)
					(justify left bottom)
				)
			)
			(property "Manufacturer" "Diodes Incorporated"
				(at 35.56 -15.24 0)
				(effects
					(font
						(size 1.27 1.27)
						(thickness 0.15)
					)
					(justify left bottom)
					(hide yes)
				)
			)
			(property "Author" "Antmicro"
				(at 35.56 -17.78 0)
				(effects
					(font
						(size 1.27 1.27)
						(thickness 0.15)
					)
					(justify left bottom)
					(hide yes)
				)
			)
			(property "License" "Apache-2.0"
				(at 35.56 -20.32 0)
				(effects
					(font
						(size 1.27 1.27)
						(thickness 0.15)
					)
					(justify left bottom)
					(hide yes)
				)
			)
			(property "ki_keywords" "SMT, PMIC, IC, VOLTAGE"
				(at 0 0 0)
				(effects
					(font
						(size 1.27 1.27)
					)
					(hide yes)
				)
			)
			(symbol "AP62301_TSOT_1_1"
				(rectangle
					(start 2.54 2.54)
					(end 17.78 -12.7)
					(stroke
						(width 0.254)
						(type default)
					)
					(fill
						(type background)
					)
				)
				(pin power_in line
					(at 0 0 0)
					(length 2.54)
					(name "VIN"
						(effects
							(font
								(size 1.27 1.27)
							)
						)
					)
					(number "3"
						(effects
							(font
								(size 1.27 1.27)
							)
						)
					)
				)
				(pin input line
					(at 0 -5.08 0)
					(length 2.54)
					(name "EN"
						(effects
							(font
								(size 1.27 1.27)
							)
						)
					)
					(number "5"
						(effects
							(font
								(size 1.27 1.27)
							)
						)
					)
				)
				(pin power_in line
					(at 0 -10.16 0)
					(length 2.54)
					(name "GND"
						(effects
							(font
								(size 1.27 1.27)
							)
						)
					)
					(number "1"
						(effects
							(font
								(size 1.27 1.27)
							)
						)
					)
				)
				(pin power_out line
					(at 20.32 0 180)
					(length 2.54)
					(name "SW"
						(effects
							(font
								(size 1.27 1.27)
							)
						)
					)
					(number "2"
						(effects
							(font
								(size 1.27 1.27)
							)
						)
					)
				)
				(pin output line
					(at 20.32 -5.08 180)
					(length 2.54)
					(name "BST"
						(effects
							(font
								(size 1.27 1.27)
							)
						)
					)
					(number "6"
						(effects
							(font
								(size 1.27 1.27)
							)
						)
					)
				)
				(pin input line
					(at 20.32 -10.16 180)
					(length 2.54)
					(name "FB"
						(effects
							(font
								(size 1.27 1.27)
							)
						)
					)
					(number "4"
						(effects
							(font
								(size 1.27 1.27)
							)
						)
					)
				)
			)
		)
	(symbol "antmicroDCDCConverters:LMR62014XMF"
			(exclude_from_sim no)
			(in_bom yes)
			(on_board yes)
			(property "Reference" "U"
				(at 30.48 -2.54 0)
				(effects
					(font
						(size 1.27 1.27)
						(thickness 0.15)
					)
					(justify left bottom)
				)
			)
			(property "Value" "LMR62014XMF"
				(at 30.48 -7.62 0)
				(effects
					(font
						(size 1.27 1.27)
						(thickness 0.15)
					)
					(justify left bottom)
					(hide yes)
				)
			)
			(property "Footprint" "antmicro-footprints:SOT-23-5"
				(at 30.48 -10.16 0)
				(effects
					(font
						(size 1.27 1.27)
						(thickness 0.15)
					)
					(justify left bottom)
					(hide yes)
				)
			)
			(property "Datasheet" "https://www.ti.com/lit/ds/symlink/lmr62014.pdf?ts=1698148381034"
				(at 30.48 -12.7 0)
				(effects
					(font
						(size 1.27 1.27)
						(thickness 0.15)
					)
					(justify left bottom)
					(hide yes)
				)
			)
			(property "Description" "Step-Up Regulator  2.7V to 14V, 1.4A"
				(at 0 0 0)
				(effects
					(font
						(size 1.27 1.27)
					)
					(hide yes)
				)
			)
			(property "Manufacturer" "Texas Instruments"
				(at 30.48 -15.24 0)
				(effects
					(font
						(size 1.27 1.27)
						(thickness 0.15)
					)
					(justify left bottom)
					(hide yes)
				)
			)
			(property "MPN" "LMR62014XMF/NOPB"
				(at 30.48 -5.08 0)
				(effects
					(font
						(size 1.27 1.27)
						(thickness 0.15)
					)
					(justify left bottom)
				)
			)
			(property "Author" "Antmicro"
				(at 30.48 -17.78 0)
				(effects
					(font
						(size 1.27 1.27)
						(thickness 0.15)
					)
					(justify left bottom)
					(hide yes)
				)
			)
			(property "License" "Apache-2.0"
				(at 30.48 -20.32 0)
				(effects
					(font
						(size 1.27 1.27)
						(thickness 0.15)
					)
					(justify left bottom)
					(hide yes)
				)
			)
			(property "ki_keywords" "SMT, PMIC, IC, POWER, MANAGEMENT, VOLTAGE, REGULATOR"
				(at 0 0 0)
				(effects
					(font
						(size 1.27 1.27)
					)
					(hide yes)
				)
			)
			(symbol "LMR62014XMF_1_1"
				(rectangle
					(start 2.54 2.54)
					(end 12.7 -7.62)
					(stroke
						(width 0.254)
						(type default)
					)
					(fill
						(type background)
					)
				)
				(pin power_in line
					(at 0 0 0)
					(length 2.54)
					(name "VIN"
						(effects
							(font
								(size 1.27 1.27)
							)
						)
					)
					(number "5"
						(effects
							(font
								(size 1.27 1.27)
							)
						)
					)
				)
				(pin input line
					(at 0 -2.54 0)
					(length 2.54)
					(name "~{SHDN}"
						(effects
							(font
								(size 1.27 1.27)
							)
						)
					)
					(number "4"
						(effects
							(font
								(size 1.27 1.27)
							)
						)
					)
				)
				(pin power_in line
					(at 0 -5.08 0)
					(length 2.54)
					(name "GND"
						(effects
							(font
								(size 1.27 1.27)
							)
						)
					)
					(number "2"
						(effects
							(font
								(size 1.27 1.27)
							)
						)
					)
				)
				(pin power_out line
					(at 15.24 0 180)
					(length 2.54)
					(name "SW"
						(effects
							(font
								(size 1.27 1.27)
							)
						)
					)
					(number "1"
						(effects
							(font
								(size 1.27 1.27)
							)
						)
					)
				)
				(pin input line
					(at 15.24 -5.08 180)
					(length 2.54)
					(name "FB"
						(effects
							(font
								(size 1.27 1.27)
							)
						)
					)
					(number "3"
						(effects
							(font
								(size 1.27 1.27)
							)
						)
					)
				)
			)
		)
	(symbol "antmicroDiodesRectifiersSingle:PMEG3010CEJ,115"
			(pin_numbers
				(hide yes)
			)
			(pin_names
				(hide yes)
			)
			(exclude_from_sim no)
			(in_bom yes)
			(on_board yes)
			(property "Reference" "D"
				(at 22.86 -5.08 0)
				(effects
					(font
						(size 1.27 1.27)
						(thickness 0.15)
					)
					(justify left bottom)
				)
			)
			(property "Value" "PMEG3010CEJ,115"
				(at 22.86 -15.24 0)
				(effects
					(font
						(size 1.27 1.27)
						(thickness 0.15)
					)
					(justify left bottom)
					(hide yes)
				)
			)
			(property "Footprint" "antmicro-footprints:D_SOD-323F"
				(at 22.86 -10.16 0)
				(effects
					(font
						(size 1.27 1.27)
						(thickness 0.15)
					)
					(justify left bottom)
					(hide yes)
				)
			)
			(property "Datasheet" "https://assets.nexperia.com/documents/data-sheet/PMEG3010CEH_PMEG3010CEJ.pdf"
				(at 22.86 -12.7 0)
				(effects
					(font
						(size 1.27 1.27)
						(thickness 0.15)
					)
					(justify left bottom)
					(hide yes)
				)
			)
			(property "Description" "Schottky Rectifier, 30 V, 1 A, Single, SOD-323F, 2 Pins, 520 mV"
				(at 0 0 0)
				(effects
					(font
						(size 1.27 1.27)
					)
					(hide yes)
				)
			)
			(property "MPN" "PMEG3010CEJ,115"
				(at 22.86 -7.62 0)
				(effects
					(font
						(size 1.27 1.27)
						(thickness 0.15)
					)
					(justify left bottom)
				)
			)
			(property "Manufacturer" "Nexperia"
				(at 22.86 -17.78 0)
				(effects
					(font
						(size 1.27 1.27)
						(thickness 0.15)
					)
					(justify left bottom)
					(hide yes)
				)
			)
			(property "Author" "Antmicro"
				(at 22.86 -20.32 0)
				(effects
					(font
						(size 1.27 1.27)
						(thickness 0.15)
					)
					(justify left bottom)
					(hide yes)
				)
			)
			(property "License" "Apache-2.0"
				(at 22.86 -22.86 0)
				(effects
					(font
						(size 1.27 1.27)
						(thickness 0.15)
					)
					(justify left bottom)
					(hide yes)
				)
			)
			(property "ki_keywords" "SMT, DIODE, SEMICONDUCTOR, RECTIFIER, SCHOTTKY"
				(at 0 0 0)
				(effects
					(font
						(size 1.27 1.27)
					)
					(hide yes)
				)
			)
			(symbol "PMEG3010CEJ,115_0_1"
				(polyline
					(pts
						(xy 1.905 0) (xy 0.635 0)
					)
					(stroke
						(width 0)
						(type default)
					)
					(fill
						(type none)
					)
				)
				(polyline
					(pts
						(xy 4.445 0) (xy 3.175 0)
					)
					(stroke
						(width 0)
						(type default)
					)
					(fill
						(type none)
					)
				)
			)
			(symbol "PMEG3010CEJ,115_1_1"
				(polyline
					(pts
						(xy 1.778 1.016) (xy 1.778 -1.016)
					)
					(stroke
						(width 0.254)
						(type default)
					)
					(fill
						(type none)
					)
				)
				(polyline
					(pts
						(xy 1.778 1.016) (xy 1.397 1.016) (xy 1.397 0.762)
					)
					(stroke
						(width 0.254)
						(type default)
					)
					(fill
						(type none)
					)
				)
				(polyline
					(pts
						(xy 1.778 -1.016) (xy 2.159 -1.016) (xy 2.159 -0.762)
					)
					(stroke
						(width 0.254)
						(type default)
					)
					(fill
						(type none)
					)
				)
				(polyline
					(pts
						(xy 3.302 1.016) (xy 3.302 -1.016) (xy 1.778 0) (xy 3.302 1.016)
					)
					(stroke
						(width 0.254)
						(type default)
					)
					(fill
						(type outline)
					)
				)
				(pin passive line
					(at 0 0 0)
					(length 0.635)
					(name "C"
						(effects
							(font
								(size 1.27 1.27)
							)
						)
					)
					(number "1"
						(effects
							(font
								(size 1.27 1.27)
							)
						)
					)
				)
				(pin passive line
					(at 5.08 0 180)
					(length 0.635)
					(name "A"
						(effects
							(font
								(size 1.27 1.27)
							)
						)
					)
					(number "2"
						(effects
							(font
								(size 1.27 1.27)
							)
						)
					)
				)
			)
		)
	(symbol "antmicroFCCConnectors:Conn_FFC_WE_68715014522"
			(exclude_from_sim no)
			(in_bom yes)
			(on_board yes)
			(property "Reference" "J"
				(at 19.05 -5.08 0)
				(effects
					(font
						(size 1.27 1.27)
						(thickness 0.15)
					)
					(justify left bottom)
				)
			)
			(property "Value" "Conn_FFC_WE_68715014522"
				(at 19.05 -7.62 0)
				(effects
					(font
						(size 1.27 1.27)
						(thickness 0.15)
					)
					(justify left bottom)
					(hide yes)
				)
			)
			(property "Footprint" "antmicro-footprints:Conn_FFC_WE_68715014x22"
				(at 19.05 -10.16 0)
				(effects
					(font
						(size 1.27 1.27)
						(thickness 0.15)
					)
					(justify left bottom)
					(hide yes)
				)
			)
			(property "Datasheet" "https://www.we-online.com/components/products/datasheet/68715014522.pdf"
				(at 19.05 -12.7 0)
				(effects
					(font
						(size 1.27 1.27)
						(thickness 0.15)
					)
					(justify left bottom)
					(hide yes)
				)
			)
			(property "Description" "FFC connector"
				(at 0 0 0)
				(effects
					(font
						(size 1.27 1.27)
					)
					(hide yes)
				)
			)
			(property "MPN" "68715014522"
				(at 19.05 -15.24 0)
				(effects
					(font
						(size 1.27 1.27)
						(thickness 0.15)
					)
					(justify left bottom)
				)
			)
			(property "Manufacturer" "Würth Elektronik"
				(at 19.05 -17.78 0)
				(effects
					(font
						(size 1.27 1.27)
						(thickness 0.15)
					)
					(justify left bottom)
					(hide yes)
				)
			)
			(property "Author" "Antmicro"
				(at 19.05 -20.32 0)
				(effects
					(font
						(size 1.27 1.27)
						(thickness 0.15)
					)
					(justify left bottom)
					(hide yes)
				)
			)
			(property "License" "Apache-2.0"
				(at 19.05 -22.86 0)
				(effects
					(font
						(size 1.27 1.27)
						(thickness 0.15)
					)
					(justify left bottom)
					(hide yes)
				)
			)
			(property "ki_keywords" "CONNECTOR"
				(at 0 0 0)
				(effects
					(font
						(size 1.27 1.27)
					)
					(hide yes)
				)
			)
			(symbol "Conn_FFC_WE_68715014522_1_1"
				(rectangle
					(start 3.81 1.27)
					(end 7.62 -132.08)
					(stroke
						(width 0.254)
						(type default)
					)
					(fill
						(type background)
					)
				)
				(rectangle
					(start 3.81 0.127)
					(end 5.08 -0.127)
					(stroke
						(width 0.254)
						(type default)
					)
					(fill
						(type background)
					)
				)
				(rectangle
					(start 3.81 -2.413)
					(end 5.08 -2.667)
					(stroke
						(width 0.254)
						(type default)
					)
					(fill
						(type background)
					)
				)
				(rectangle
					(start 3.81 -4.953)
					(end 5.08 -5.207)
					(stroke
						(width 0.254)
						(type default)
					)
					(fill
						(type background)
					)
				)
				(rectangle
					(start 3.81 -7.493)
					(end 5.08 -7.747)
					(stroke
						(width 0.254)
						(type default)
					)
					(fill
						(type background)
					)
				)
				(rectangle
					(start 3.81 -10.033)
					(end 5.08 -10.287)
					(stroke
						(width 0.254)
						(type default)
					)
					(fill
						(type background)
					)
				)
				(rectangle
					(start 3.81 -12.573)
					(end 5.08 -12.827)
					(stroke
						(width 0.254)
						(type default)
					)
					(fill
						(type background)
					)
				)
				(rectangle
					(start 3.81 -15.113)
					(end 5.08 -15.367)
					(stroke
						(width 0.254)
						(type default)
					)
					(fill
						(type background)
					)
				)
				(rectangle
					(start 3.81 -17.653)
					(end 5.08 -17.907)
					(stroke
						(width 0.254)
						(type default)
					)
					(fill
						(type background)
					)
				)
				(rectangle
					(start 3.81 -20.193)
					(end 5.08 -20.447)
					(stroke
						(width 0.254)
						(type default)
					)
					(fill
						(type background)
					)
				)
				(rectangle
					(start 3.81 -22.733)
					(end 5.08 -22.987)
					(stroke
						(width 0.254)
						(type default)
					)
					(fill
						(type background)
					)
				)
				(rectangle
					(start 3.81 -25.273)
					(end 5.08 -25.527)
					(stroke
						(width 0.254)
						(type default)
					)
					(fill
						(type background)
					)
				)
				(rectangle
					(start 3.81 -27.813)
					(end 5.08 -28.067)
					(stroke
						(width 0.254)
						(type default)
					)
					(fill
						(type background)
					)
				)
				(rectangle
					(start 3.81 -30.353)
					(end 5.08 -30.607)
					(stroke
						(width 0.254)
						(type default)
					)
					(fill
						(type background)
					)
				)
				(rectangle
					(start 3.81 -32.893)
					(end 5.08 -33.147)
					(stroke
						(width 0.254)
						(type default)
					)
					(fill
						(type background)
					)
				)
				(rectangle
					(start 3.81 -35.433)
					(end 5.08 -35.687)
					(stroke
						(width 0.254)
						(type default)
					)
					(fill
						(type background)
					)
				)
				(rectangle
					(start 3.81 -37.973)
					(end 5.08 -38.227)
					(stroke
						(width 0.254)
						(type default)
					)
					(fill
						(type background)
					)
				)
				(rectangle
					(start 3.81 -40.513)
					(end 5.08 -40.767)
					(stroke
						(width 0.254)
						(type default)
					)
					(fill
						(type background)
					)
				)
				(rectangle
					(start 3.81 -43.053)
					(end 5.08 -43.307)
					(stroke
						(width 0.254)
						(type default)
					)
					(fill
						(type background)
					)
				)
				(rectangle
					(start 3.81 -45.593)
					(end 5.08 -45.847)
					(stroke
						(width 0.254)
						(type default)
					)
					(fill
						(type background)
					)
				)
				(rectangle
					(start 3.81 -48.133)
					(end 5.08 -48.387)
					(stroke
						(width 0.254)
						(type default)
					)
					(fill
						(type background)
					)
				)
				(rectangle
					(start 3.81 -50.673)
					(end 5.08 -50.927)
					(stroke
						(width 0.254)
						(type default)
					)
					(fill
						(type background)
					)
				)
				(rectangle
					(start 3.81 -53.213)
					(end 5.08 -53.467)
					(stroke
						(width 0.254)
						(type default)
					)
					(fill
						(type background)
					)
				)
				(rectangle
					(start 3.81 -55.753)
					(end 5.08 -56.007)
					(stroke
						(width 0.254)
						(type default)
					)
					(fill
						(type background)
					)
				)
				(rectangle
					(start 3.81 -58.293)
					(end 5.08 -58.547)
					(stroke
						(width 0.254)
						(type default)
					)
					(fill
						(type background)
					)
				)
				(rectangle
					(start 3.81 -60.833)
					(end 5.08 -61.087)
					(stroke
						(width 0.254)
						(type default)
					)
					(fill
						(type background)
					)
				)
				(rectangle
					(start 3.81 -63.373)
					(end 5.08 -63.627)
					(stroke
						(width 0.254)
						(type default)
					)
					(fill
						(type background)
					)
				)
				(rectangle
					(start 3.81 -65.913)
					(end 5.08 -66.167)
					(stroke
						(width 0.254)
						(type default)
					)
					(fill
						(type background)
					)
				)
				(rectangle
					(start 3.81 -68.453)
					(end 5.08 -68.707)
					(stroke
						(width 0.254)
						(type default)
					)
					(fill
						(type background)
					)
				)
				(rectangle
					(start 3.81 -70.993)
					(end 5.08 -71.247)
					(stroke
						(width 0.254)
						(type default)
					)
					(fill
						(type background)
					)
				)
				(rectangle
					(start 3.81 -73.533)
					(end 5.08 -73.787)
					(stroke
						(width 0.254)
						(type default)
					)
					(fill
						(type background)
					)
				)
				(rectangle
					(start 3.81 -76.073)
					(end 5.08 -76.327)
					(stroke
						(width 0.254)
						(type default)
					)
					(fill
						(type background)
					)
				)
				(rectangle
					(start 3.81 -78.613)
					(end 5.08 -78.867)
					(stroke
						(width 0.254)
						(type default)
					)
					(fill
						(type background)
					)
				)
				(rectangle
					(start 3.81 -81.153)
					(end 5.08 -81.407)
					(stroke
						(width 0.254)
						(type default)
					)
					(fill
						(type background)
					)
				)
				(rectangle
					(start 3.81 -83.693)
					(end 5.08 -83.947)
					(stroke
						(width 0.254)
						(type default)
					)
					(fill
						(type background)
					)
				)
				(rectangle
					(start 3.81 -86.233)
					(end 5.08 -86.487)
					(stroke
						(width 0.254)
						(type default)
					)
					(fill
						(type background)
					)
				)
				(rectangle
					(start 3.81 -88.773)
					(end 5.08 -89.027)
					(stroke
						(width 0.254)
						(type default)
					)
					(fill
						(type background)
					)
				)
				(rectangle
					(start 3.81 -91.313)
					(end 5.08 -91.567)
					(stroke
						(width 0.254)
						(type default)
					)
					(fill
						(type background)
					)
				)
				(rectangle
					(start 3.81 -93.853)
					(end 5.08 -94.107)
					(stroke
						(width 0.254)
						(type default)
					)
					(fill
						(type background)
					)
				)
				(rectangle
					(start 3.81 -96.393)
					(end 5.08 -96.647)
					(stroke
						(width 0.254)
						(type default)
					)
					(fill
						(type background)
					)
				)
				(rectangle
					(start 3.81 -98.933)
					(end 5.08 -99.187)
					(stroke
						(width 0.254)
						(type default)
					)
					(fill
						(type background)
					)
				)
				(rectangle
					(start 3.81 -101.473)
					(end 5.08 -101.727)
					(stroke
						(width 0.254)
						(type default)
					)
					(fill
						(type background)
					)
				)
				(rectangle
					(start 3.81 -104.013)
					(end 5.08 -104.267)
					(stroke
						(width 0.254)
						(type default)
					)
					(fill
						(type background)
					)
				)
				(rectangle
					(start 3.81 -106.553)
					(end 5.08 -106.807)
					(stroke
						(width 0.254)
						(type default)
					)
					(fill
						(type background)
					)
				)
				(rectangle
					(start 3.81 -109.093)
					(end 5.08 -109.347)
					(stroke
						(width 0.254)
						(type default)
					)
					(fill
						(type background)
					)
				)
				(rectangle
					(start 3.81 -111.633)
					(end 5.08 -111.887)
					(stroke
						(width 0.254)
						(type default)
					)
					(fill
						(type background)
					)
				)
				(rectangle
					(start 3.81 -114.173)
					(end 5.08 -114.427)
					(stroke
						(width 0.254)
						(type default)
					)
					(fill
						(type background)
					)
				)
				(rectangle
					(start 3.81 -116.713)
					(end 5.08 -116.967)
					(stroke
						(width 0.254)
						(type default)
					)
					(fill
						(type background)
					)
				)
				(rectangle
					(start 3.81 -119.253)
					(end 5.08 -119.507)
					(stroke
						(width 0.254)
						(type default)
					)
					(fill
						(type background)
					)
				)
				(rectangle
					(start 3.81 -121.793)
					(end 5.08 -122.047)
					(stroke
						(width 0.254)
						(type default)
					)
					(fill
						(type background)
					)
				)
				(rectangle
					(start 3.81 -124.333)
					(end 5.08 -124.587)
					(stroke
						(width 0.254)
						(type default)
					)
					(fill
						(type background)
					)
				)
				(pin passive line
					(at 0 0 0)
					(length 3.81)
					(name "~"
						(effects
							(font
								(size 1.27 1.27)
							)
						)
					)
					(number "1"
						(effects
							(font
								(size 1.27 1.27)
							)
						)
					)
				)
				(pin passive line
					(at 0 -2.54 0)
					(length 3.81)
					(name "~"
						(effects
							(font
								(size 1.27 1.27)
							)
						)
					)
					(number "2"
						(effects
							(font
								(size 1.27 1.27)
							)
						)
					)
				)
				(pin passive line
					(at 0 -5.08 0)
					(length 3.81)
					(name "~"
						(effects
							(font
								(size 1.27 1.27)
							)
						)
					)
					(number "3"
						(effects
							(font
								(size 1.27 1.27)
							)
						)
					)
				)
				(pin passive line
					(at 0 -7.62 0)
					(length 3.81)
					(name "~"
						(effects
							(font
								(size 1.27 1.27)
							)
						)
					)
					(number "4"
						(effects
							(font
								(size 1.27 1.27)
							)
						)
					)
				)
				(pin passive line
					(at 0 -10.16 0)
					(length 3.81)
					(name "~"
						(effects
							(font
								(size 1.27 1.27)
							)
						)
					)
					(number "5"
						(effects
							(font
								(size 1.27 1.27)
							)
						)
					)
				)
				(pin passive line
					(at 0 -12.7 0)
					(length 3.81)
					(name "~"
						(effects
							(font
								(size 1.27 1.27)
							)
						)
					)
					(number "6"
						(effects
							(font
								(size 1.27 1.27)
							)
						)
					)
				)
				(pin passive line
					(at 0 -15.24 0)
					(length 3.81)
					(name "~"
						(effects
							(font
								(size 1.27 1.27)
							)
						)
					)
					(number "7"
						(effects
							(font
								(size 1.27 1.27)
							)
						)
					)
				)
				(pin passive line
					(at 0 -17.78 0)
					(length 3.81)
					(name "~"
						(effects
							(font
								(size 1.27 1.27)
							)
						)
					)
					(number "8"
						(effects
							(font
								(size 1.27 1.27)
							)
						)
					)
				)
				(pin passive line
					(at 0 -20.32 0)
					(length 3.81)
					(name "~"
						(effects
							(font
								(size 1.27 1.27)
							)
						)
					)
					(number "9"
						(effects
							(font
								(size 1.27 1.27)
							)
						)
					)
				)
				(pin passive line
					(at 0 -22.86 0)
					(length 3.81)
					(name "~"
						(effects
							(font
								(size 1.27 1.27)
							)
						)
					)
					(number "10"
						(effects
							(font
								(size 1.27 1.27)
							)
						)
					)
				)
				(pin passive line
					(at 0 -25.4 0)
					(length 3.81)
					(name "~"
						(effects
							(font
								(size 1.27 1.27)
							)
						)
					)
					(number "11"
						(effects
							(font
								(size 1.27 1.27)
							)
						)
					)
				)
				(pin passive line
					(at 0 -27.94 0)
					(length 3.81)
					(name "~"
						(effects
							(font
								(size 1.27 1.27)
							)
						)
					)
					(number "12"
						(effects
							(font
								(size 1.27 1.27)
							)
						)
					)
				)
				(pin passive line
					(at 0 -30.48 0)
					(length 3.81)
					(name "~"
						(effects
							(font
								(size 1.27 1.27)
							)
						)
					)
					(number "13"
						(effects
							(font
								(size 1.27 1.27)
							)
						)
					)
				)
				(pin passive line
					(at 0 -33.02 0)
					(length 3.81)
					(name "~"
						(effects
							(font
								(size 1.27 1.27)
							)
						)
					)
					(number "14"
						(effects
							(font
								(size 1.27 1.27)
							)
						)
					)
				)
				(pin passive line
					(at 0 -35.56 0)
					(length 3.81)
					(name "~"
						(effects
							(font
								(size 1.27 1.27)
							)
						)
					)
					(number "15"
						(effects
							(font
								(size 1.27 1.27)
							)
						)
					)
				)
				(pin passive line
					(at 0 -38.1 0)
					(length 3.81)
					(name "~"
						(effects
							(font
								(size 1.27 1.27)
							)
						)
					)
					(number "16"
						(effects
							(font
								(size 1.27 1.27)
							)
						)
					)
				)
				(pin passive line
					(at 0 -40.64 0)
					(length 3.81)
					(name "~"
						(effects
							(font
								(size 1.27 1.27)
							)
						)
					)
					(number "17"
						(effects
							(font
								(size 1.27 1.27)
							)
						)
					)
				)
				(pin passive line
					(at 0 -43.18 0)
					(length 3.81)
					(name "~"
						(effects
							(font
								(size 1.27 1.27)
							)
						)
					)
					(number "18"
						(effects
							(font
								(size 1.27 1.27)
							)
						)
					)
				)
				(pin passive line
					(at 0 -45.72 0)
					(length 3.81)
					(name "~"
						(effects
							(font
								(size 1.27 1.27)
							)
						)
					)
					(number "19"
						(effects
							(font
								(size 1.27 1.27)
							)
						)
					)
				)
				(pin passive line
					(at 0 -48.26 0)
					(length 3.81)
					(name "~"
						(effects
							(font
								(size 1.27 1.27)
							)
						)
					)
					(number "20"
						(effects
							(font
								(size 1.27 1.27)
							)
						)
					)
				)
				(pin passive line
					(at 0 -50.8 0)
					(length 3.81)
					(name "~"
						(effects
							(font
								(size 1.27 1.27)
							)
						)
					)
					(number "21"
						(effects
							(font
								(size 1.27 1.27)
							)
						)
					)
				)
				(pin passive line
					(at 0 -53.34 0)
					(length 3.81)
					(name "~"
						(effects
							(font
								(size 1.27 1.27)
							)
						)
					)
					(number "22"
						(effects
							(font
								(size 1.27 1.27)
							)
						)
					)
				)
				(pin passive line
					(at 0 -55.88 0)
					(length 3.81)
					(name "~"
						(effects
							(font
								(size 1.27 1.27)
							)
						)
					)
					(number "23"
						(effects
							(font
								(size 1.27 1.27)
							)
						)
					)
				)
				(pin passive line
					(at 0 -58.42 0)
					(length 3.81)
					(name "~"
						(effects
							(font
								(size 1.27 1.27)
							)
						)
					)
					(number "24"
						(effects
							(font
								(size 1.27 1.27)
							)
						)
					)
				)
				(pin passive line
					(at 0 -60.96 0)
					(length 3.81)
					(name "~"
						(effects
							(font
								(size 1.27 1.27)
							)
						)
					)
					(number "25"
						(effects
							(font
								(size 1.27 1.27)
							)
						)
					)
				)
				(pin passive line
					(at 0 -63.5 0)
					(length 3.81)
					(name "~"
						(effects
							(font
								(size 1.27 1.27)
							)
						)
					)
					(number "26"
						(effects
							(font
								(size 1.27 1.27)
							)
						)
					)
				)
				(pin passive line
					(at 0 -66.04 0)
					(length 3.81)
					(name "~"
						(effects
							(font
								(size 1.27 1.27)
							)
						)
					)
					(number "27"
						(effects
							(font
								(size 1.27 1.27)
							)
						)
					)
				)
				(pin passive line
					(at 0 -68.58 0)
					(length 3.81)
					(name "~"
						(effects
							(font
								(size 1.27 1.27)
							)
						)
					)
					(number "28"
						(effects
							(font
								(size 1.27 1.27)
							)
						)
					)
				)
				(pin passive line
					(at 0 -71.12 0)
					(length 3.81)
					(name "~"
						(effects
							(font
								(size 1.27 1.27)
							)
						)
					)
					(number "29"
						(effects
							(font
								(size 1.27 1.27)
							)
						)
					)
				)
				(pin passive line
					(at 0 -73.66 0)
					(length 3.81)
					(name "~"
						(effects
							(font
								(size 1.27 1.27)
							)
						)
					)
					(number "30"
						(effects
							(font
								(size 1.27 1.27)
							)
						)
					)
				)
				(pin passive line
					(at 0 -76.2 0)
					(length 3.81)
					(name "~"
						(effects
							(font
								(size 1.27 1.27)
							)
						)
					)
					(number "31"
						(effects
							(font
								(size 1.27 1.27)
							)
						)
					)
				)
				(pin passive line
					(at 0 -78.74 0)
					(length 3.81)
					(name "~"
						(effects
							(font
								(size 1.27 1.27)
							)
						)
					)
					(number "32"
						(effects
							(font
								(size 1.27 1.27)
							)
						)
					)
				)
				(pin passive line
					(at 0 -81.28 0)
					(length 3.81)
					(name "~"
						(effects
							(font
								(size 1.27 1.27)
							)
						)
					)
					(number "33"
						(effects
							(font
								(size 1.27 1.27)
							)
						)
					)
				)
				(pin passive line
					(at 0 -83.82 0)
					(length 3.81)
					(name "~"
						(effects
							(font
								(size 1.27 1.27)
							)
						)
					)
					(number "34"
						(effects
							(font
								(size 1.27 1.27)
							)
						)
					)
				)
				(pin passive line
					(at 0 -86.36 0)
					(length 3.81)
					(name "~"
						(effects
							(font
								(size 1.27 1.27)
							)
						)
					)
					(number "35"
						(effects
							(font
								(size 1.27 1.27)
							)
						)
					)
				)
				(pin passive line
					(at 0 -88.9 0)
					(length 3.81)
					(name "~"
						(effects
							(font
								(size 1.27 1.27)
							)
						)
					)
					(number "36"
						(effects
							(font
								(size 1.27 1.27)
							)
						)
					)
				)
				(pin passive line
					(at 0 -91.44 0)
					(length 3.81)
					(name "~"
						(effects
							(font
								(size 1.27 1.27)
							)
						)
					)
					(number "37"
						(effects
							(font
								(size 1.27 1.27)
							)
						)
					)
				)
				(pin passive line
					(at 0 -93.98 0)
					(length 3.81)
					(name "~"
						(effects
							(font
								(size 1.27 1.27)
							)
						)
					)
					(number "38"
						(effects
							(font
								(size 1.27 1.27)
							)
						)
					)
				)
				(pin passive line
					(at 0 -96.52 0)
					(length 3.81)
					(name "~"
						(effects
							(font
								(size 1.27 1.27)
							)
						)
					)
					(number "39"
						(effects
							(font
								(size 1.27 1.27)
							)
						)
					)
				)
				(pin passive line
					(at 0 -99.06 0)
					(length 3.81)
					(name "~"
						(effects
							(font
								(size 1.27 1.27)
							)
						)
					)
					(number "40"
						(effects
							(font
								(size 1.27 1.27)
							)
						)
					)
				)
				(pin passive line
					(at 0 -101.6 0)
					(length 3.81)
					(name "~"
						(effects
							(font
								(size 1.27 1.27)
							)
						)
					)
					(number "41"
						(effects
							(font
								(size 1.27 1.27)
							)
						)
					)
				)
				(pin passive line
					(at 0 -104.14 0)
					(length 3.81)
					(name "~"
						(effects
							(font
								(size 1.27 1.27)
							)
						)
					)
					(number "42"
						(effects
							(font
								(size 1.27 1.27)
							)
						)
					)
				)
				(pin passive line
					(at 0 -106.68 0)
					(length 3.81)
					(name "~"
						(effects
							(font
								(size 1.27 1.27)
							)
						)
					)
					(number "43"
						(effects
							(font
								(size 1.27 1.27)
							)
						)
					)
				)
				(pin passive line
					(at 0 -109.22 0)
					(length 3.81)
					(name "~"
						(effects
							(font
								(size 1.27 1.27)
							)
						)
					)
					(number "44"
						(effects
							(font
								(size 1.27 1.27)
							)
						)
					)
				)
				(pin passive line
					(at 0 -111.76 0)
					(length 3.81)
					(name "~"
						(effects
							(font
								(size 1.27 1.27)
							)
						)
					)
					(number "45"
						(effects
							(font
								(size 1.27 1.27)
							)
						)
					)
				)
				(pin passive line
					(at 0 -114.3 0)
					(length 3.81)
					(name "~"
						(effects
							(font
								(size 1.27 1.27)
							)
						)
					)
					(number "46"
						(effects
							(font
								(size 1.27 1.27)
							)
						)
					)
				)
				(pin passive line
					(at 0 -116.84 0)
					(length 3.81)
					(name "~"
						(effects
							(font
								(size 1.27 1.27)
							)
						)
					)
					(number "47"
						(effects
							(font
								(size 1.27 1.27)
							)
						)
					)
				)
				(pin passive line
					(at 0 -119.38 0)
					(length 3.81)
					(name "~"
						(effects
							(font
								(size 1.27 1.27)
							)
						)
					)
					(number "48"
						(effects
							(font
								(size 1.27 1.27)
							)
						)
					)
				)
				(pin passive line
					(at 0 -121.92 0)
					(length 3.81)
					(name "~"
						(effects
							(font
								(size 1.27 1.27)
							)
						)
					)
					(number "49"
						(effects
							(font
								(size 1.27 1.27)
							)
						)
					)
				)
				(pin passive line
					(at 0 -124.46 0)
					(length 3.81)
					(name "~"
						(effects
							(font
								(size 1.27 1.27)
							)
						)
					)
					(number "50"
						(effects
							(font
								(size 1.27 1.27)
							)
						)
					)
				)
				(pin passive line
					(at 0 -127 0)
					(length 3.81)
					(name "MP"
						(effects
							(font
								(size 1.27 1.27)
							)
						)
					)
					(number "MP1"
						(effects
							(font
								(size 1.27 1.27)
							)
						)
					)
				)
				(pin passive line
					(at 0 -129.54 0)
					(length 3.81)
					(name "MP"
						(effects
							(font
								(size 1.27 1.27)
							)
						)
					)
					(number "MP2"
						(effects
							(font
								(size 1.27 1.27)
							)
						)
					)
				)
			)
		)
	(symbol "antmicroFixedInductors:L_10u_3.1A_Bourns-SRN8040"
			(pin_numbers
				(hide yes)
			)
			(pin_names
				(hide yes)
			)
			(exclude_from_sim no)
			(in_bom yes)
			(on_board yes)
			(property "Reference" "L"
				(at 13.97 0 0)
				(effects
					(font
						(size 1.27 1.27)
						(thickness 0.15)
					)
					(justify left bottom)
				)
			)
			(property "Value" "L_10u_3.1A_Bourns-SRN8040"
				(at 13.97 -2.54 0)
				(effects
					(font
						(size 1.27 1.27)
						(thickness 0.15)
					)
					(justify left bottom)
					(hide yes)
				)
			)
			(property "Footprint" "antmicro-footprints:L_Bourns-SRN8040"
				(at 13.97 -7.62 0)
				(effects
					(font
						(size 1.27 1.27)
						(thickness 0.15)
					)
					(justify left bottom)
					(hide yes)
				)
			)
			(property "Datasheet" "https://www.bourns.com/pdfs/SRN8040.pdf"
				(at 13.97 -10.16 0)
				(effects
					(font
						(size 1.27 1.27)
						(thickness 0.15)
					)
					(justify left bottom)
					(hide yes)
				)
			)
			(property "Description" "Power Inductor (SMD), 10 µH, 3.1 A, Shielded, 3.4 A, SRN8040"
				(at 0 0 0)
				(effects
					(font
						(size 1.27 1.27)
					)
					(hide yes)
				)
			)
			(property "Val" "10u/3.1A"
				(at 13.97 -5.08 0)
				(effects
					(font
						(size 1.27 1.27)
						(thickness 0.15)
					)
					(justify left bottom)
				)
			)
			(property "Manufacturer" "Bourns"
				(at 13.97 -12.7 0)
				(effects
					(font
						(size 1.27 1.27)
						(thickness 0.15)
					)
					(justify left bottom)
					(hide yes)
				)
			)
			(property "MPN" "SRN8040-100M"
				(at 13.97 -15.24 0)
				(effects
					(font
						(size 1.27 1.27)
						(thickness 0.15)
					)
					(justify left bottom)
					(hide yes)
				)
			)
			(property "ISat" "3.4 A"
				(at 13.97 -16.51 0)
				(effects
					(font
						(size 1.27 1.27)
					)
					(justify left)
					(hide yes)
				)
			)
			(property "IMax" "3.1 A"
				(at 13.97 -20.32 0)
				(effects
					(font
						(size 1.27 1.27)
						(thickness 0.15)
					)
					(justify left bottom)
					(hide yes)
				)
			)
			(property "Size" "8.0x8.0"
				(at 13.97 -22.86 0)
				(effects
					(font
						(size 1.27 1.27)
						(thickness 0.15)
					)
					(justify left bottom)
					(hide yes)
				)
			)
			(property "Author" "Antmicro"
				(at 13.97 -25.4 0)
				(effects
					(font
						(size 1.27 1.27)
						(thickness 0.15)
					)
					(justify left bottom)
					(hide yes)
				)
			)
			(property "License" "Apache-2.0"
				(at 13.97 -27.94 0)
				(effects
					(font
						(size 1.27 1.27)
						(thickness 0.15)
					)
					(justify left bottom)
					(hide yes)
				)
			)
			(property "ki_keywords" "SMT, INDUCTOR, PASSIVE"
				(at 0 0 0)
				(effects
					(font
						(size 1.27 1.27)
					)
					(hide yes)
				)
			)
			(symbol "L_10u_3.1A_Bourns-SRN8040_0_1"
				(arc
					(start 0.508 0)
					(mid 1.016 0.5058)
					(end 1.524 0)
					(stroke
						(width 0)
						(type default)
					)
					(fill
						(type none)
					)
				)
				(arc
					(start 1.524 0)
					(mid 2.032 0.5058)
					(end 2.54 0)
					(stroke
						(width 0)
						(type default)
					)
					(fill
						(type none)
					)
				)
				(arc
					(start 2.54 0)
					(mid 3.048 0.5058)
					(end 3.556 0)
					(stroke
						(width 0)
						(type default)
					)
					(fill
						(type none)
					)
				)
				(arc
					(start 3.556 0)
					(mid 4.064 0.5058)
					(end 4.572 0)
					(stroke
						(width 0)
						(type default)
					)
					(fill
						(type none)
					)
				)
			)
			(symbol "L_10u_3.1A_Bourns-SRN8040_1_1"
				(pin passive line
					(at 0 0 0)
					(length 0.508)
					(name "~"
						(effects
							(font
								(size 1.27 1.27)
							)
						)
					)
					(number "1"
						(effects
							(font
								(size 1.27 1.27)
							)
						)
					)
				)
				(pin passive line
					(at 5.08 0 180)
					(length 0.508)
					(name "~"
						(effects
							(font
								(size 1.27 1.27)
							)
						)
					)
					(number "2"
						(effects
							(font
								(size 1.27 1.27)
							)
						)
					)
				)
			)
		)
	(symbol "antmicroFixedInductors:L_1u_2.6A_0806"
			(pin_numbers
				(hide yes)
			)
			(pin_names
				(hide yes)
			)
			(exclude_from_sim no)
			(in_bom yes)
			(on_board yes)
			(property "Reference" "L"
				(at 13.97 0 0)
				(effects
					(font
						(size 1.27 1.27)
						(thickness 0.15)
					)
					(justify left bottom)
				)
			)
			(property "Value" "L_1u_2.6A_0806"
				(at 13.97 -2.54 0)
				(effects
					(font
						(size 1.27 1.27)
						(thickness 0.15)
					)
					(justify left bottom)
					(hide yes)
				)
			)
			(property "Footprint" "antmicro-footprints:L_0806_2016Metric"
				(at 13.97 -7.62 0)
				(effects
					(font
						(size 1.27 1.27)
						(thickness 0.15)
					)
					(justify left bottom)
					(hide yes)
				)
			)
			(property "Datasheet" "https://www.bourns.com/docs/Product-Datasheets/SRP2010.pdf"
				(at 13.97 -10.16 0)
				(effects
					(font
						(size 1.27 1.27)
						(thickness 0.15)
					)
					(justify left bottom)
					(hide yes)
				)
			)
			(property "Description" "Wirewound Inductor, 1 µH, 0.072 ohm, 2.6 A, SRP2010"
				(at 0 0 0)
				(effects
					(font
						(size 1.27 1.27)
					)
					(hide yes)
				)
			)
			(property "Val" "1u/2.6A"
				(at 13.97 -5.08 0)
				(effects
					(font
						(size 1.27 1.27)
						(thickness 0.15)
					)
					(justify left bottom)
				)
			)
			(property "Manufacturer" "Bourns"
				(at 13.97 -12.7 0)
				(effects
					(font
						(size 1.27 1.27)
						(thickness 0.15)
					)
					(justify left bottom)
					(hide yes)
				)
			)
			(property "MPN" "SRP2010-1R0M"
				(at 13.97 -15.24 0)
				(effects
					(font
						(size 1.27 1.27)
						(thickness 0.15)
					)
					(justify left bottom)
					(hide yes)
				)
			)
			(property "ISat" "2.9 A"
				(at 13.97 -16.51 0)
				(effects
					(font
						(size 1.27 1.27)
					)
					(justify left)
					(hide yes)
				)
			)
			(property "IMax" "2.6 A"
				(at 13.97 -20.32 0)
				(effects
					(font
						(size 1.27 1.27)
						(thickness 0.15)
					)
					(justify left bottom)
					(hide yes)
				)
			)
			(property "Size" "2.0x1.6"
				(at 13.97 -22.86 0)
				(effects
					(font
						(size 1.27 1.27)
						(thickness 0.15)
					)
					(justify left bottom)
					(hide yes)
				)
			)
			(property "Author" "Antmicro"
				(at 13.97 -25.4 0)
				(effects
					(font
						(size 1.27 1.27)
						(thickness 0.15)
					)
					(justify left bottom)
					(hide yes)
				)
			)
			(property "License" "Apache-2.0"
				(at 13.97 -27.94 0)
				(effects
					(font
						(size 1.27 1.27)
						(thickness 0.15)
					)
					(justify left bottom)
					(hide yes)
				)
			)
			(property "ki_keywords" "SMT, INDUCTOR, PASSIVE"
				(at 0 0 0)
				(effects
					(font
						(size 1.27 1.27)
					)
					(hide yes)
				)
			)
			(symbol "L_1u_2.6A_0806_0_1"
				(arc
					(start 0.508 0)
					(mid 1.016 0.5058)
					(end 1.524 0)
					(stroke
						(width 0)
						(type default)
					)
					(fill
						(type none)
					)
				)
				(arc
					(start 1.524 0)
					(mid 2.032 0.5058)
					(end 2.54 0)
					(stroke
						(width 0)
						(type default)
					)
					(fill
						(type none)
					)
				)
				(arc
					(start 2.54 0)
					(mid 3.048 0.5058)
					(end 3.556 0)
					(stroke
						(width 0)
						(type default)
					)
					(fill
						(type none)
					)
				)
				(arc
					(start 3.556 0)
					(mid 4.064 0.5058)
					(end 4.572 0)
					(stroke
						(width 0)
						(type default)
					)
					(fill
						(type none)
					)
				)
			)
			(symbol "L_1u_2.6A_0806_1_1"
				(pin passive line
					(at 0 0 0)
					(length 0.508)
					(name "~"
						(effects
							(font
								(size 1.27 1.27)
							)
						)
					)
					(number "1"
						(effects
							(font
								(size 1.27 1.27)
							)
						)
					)
				)
				(pin passive line
					(at 5.08 0 180)
					(length 0.508)
					(name "~"
						(effects
							(font
								(size 1.27 1.27)
							)
						)
					)
					(number "2"
						(effects
							(font
								(size 1.27 1.27)
							)
						)
					)
				)
			)
		)
	(symbol "antmicroFixedInductors:L_22u_1.12A_Coilcraft-MSS6132T"
			(pin_numbers
				(hide yes)
			)
			(pin_names
				(hide yes)
			)
			(exclude_from_sim no)
			(in_bom yes)
			(on_board yes)
			(property "Reference" "L"
				(at 13.97 0 0)
				(effects
					(font
						(size 1.27 1.27)
						(thickness 0.15)
					)
					(justify left bottom)
				)
			)
			(property "Value" "L_22u_1.12A_Coilcraft-MSS6132T"
				(at 13.97 -2.54 0)
				(effects
					(font
						(size 1.27 1.27)
						(thickness 0.15)
					)
					(justify left bottom)
					(hide yes)
				)
			)
			(property "Footprint" "antmicro-footprints:L_Coilcraft-MSS6132T"
				(at 13.97 -7.62 0)
				(effects
					(font
						(size 1.27 1.27)
						(thickness 0.15)
					)
					(justify left bottom)
					(hide yes)
				)
			)
			(property "Datasheet" "https://www.coilcraft.com/getmedia/d035c9b3-191d-46aa-ab3f-5c1a849157c1/mss6132t.pdf"
				(at 13.97 -10.16 0)
				(effects
					(font
						(size 1.27 1.27)
						(thickness 0.15)
					)
					(justify left bottom)
					(hide yes)
				)
			)
			(property "Description" "Power Inductor (SMT), 22 µH, 1.85 A, Shielded, 2.45 A, WE-MAPI"
				(at 0 0 0)
				(effects
					(font
						(size 1.27 1.27)
					)
					(hide yes)
				)
			)
			(property "Val" "22u/1.12A"
				(at 13.97 -5.08 0)
				(effects
					(font
						(size 1.27 1.27)
						(thickness 0.15)
					)
					(justify left bottom)
				)
			)
			(property "Manufacturer" "Coilcraft"
				(at 13.97 -12.7 0)
				(effects
					(font
						(size 1.27 1.27)
						(thickness 0.15)
					)
					(justify left bottom)
					(hide yes)
				)
			)
			(property "MPN" "MSS6132T-223"
				(at 13.97 -15.24 0)
				(effects
					(font
						(size 1.27 1.27)
						(thickness 0.15)
					)
					(justify left bottom)
					(hide yes)
				)
			)
			(property "ISat" "1.12A"
				(at 13.97 -16.51 0)
				(effects
					(font
						(size 1.27 1.27)
					)
					(justify left)
					(hide yes)
				)
			)
			(property "IMax" "1.45A"
				(at 13.97 -20.32 0)
				(effects
					(font
						(size 1.27 1.27)
						(thickness 0.15)
					)
					(justify left bottom)
					(hide yes)
				)
			)
			(property "Size" "6.1x6.1"
				(at 13.97 -22.86 0)
				(effects
					(font
						(size 1.27 1.27)
						(thickness 0.15)
					)
					(justify left bottom)
					(hide yes)
				)
			)
			(property "Author" "Antmicro"
				(at 13.97 -25.4 0)
				(effects
					(font
						(size 1.27 1.27)
						(thickness 0.15)
					)
					(justify left bottom)
					(hide yes)
				)
			)
			(property "License" "Apache-2.0"
				(at 13.97 -27.94 0)
				(effects
					(font
						(size 1.27 1.27)
						(thickness 0.15)
					)
					(justify left bottom)
					(hide yes)
				)
			)
			(property "ki_keywords" "SMT, INDUCTOR, PASSIVE"
				(at 0 0 0)
				(effects
					(font
						(size 1.27 1.27)
					)
					(hide yes)
				)
			)
			(symbol "L_22u_1.12A_Coilcraft-MSS6132T_0_1"
				(arc
					(start 0.508 0)
					(mid 1.016 0.5058)
					(end 1.524 0)
					(stroke
						(width 0)
						(type default)
					)
					(fill
						(type none)
					)
				)
				(arc
					(start 1.524 0)
					(mid 2.032 0.5058)
					(end 2.54 0)
					(stroke
						(width 0)
						(type default)
					)
					(fill
						(type none)
					)
				)
				(arc
					(start 2.54 0)
					(mid 3.048 0.5058)
					(end 3.556 0)
					(stroke
						(width 0)
						(type default)
					)
					(fill
						(type none)
					)
				)
				(arc
					(start 3.556 0)
					(mid 4.064 0.5058)
					(end 4.572 0)
					(stroke
						(width 0)
						(type default)
					)
					(fill
						(type none)
					)
				)
			)
			(symbol "L_22u_1.12A_Coilcraft-MSS6132T_1_1"
				(pin passive line
					(at 0 0 0)
					(length 0.508)
					(name "~"
						(effects
							(font
								(size 1.27 1.27)
							)
						)
					)
					(number "1"
						(effects
							(font
								(size 1.27 1.27)
							)
						)
					)
				)
				(pin passive line
					(at 5.08 0 180)
					(length 0.508)
					(name "~"
						(effects
							(font
								(size 1.27 1.27)
							)
						)
					)
					(number "2"
						(effects
							(font
								(size 1.27 1.27)
							)
						)
					)
				)
			)
		)
	(symbol "antmicroFixedInductors:L_470n_1A_Coilcraft-PFL1609"
			(pin_numbers
				(hide yes)
			)
			(pin_names
				(hide yes)
			)
			(exclude_from_sim no)
			(in_bom yes)
			(on_board yes)
			(property "Reference" "L"
				(at 13.97 0 0)
				(effects
					(font
						(size 1.27 1.27)
						(thickness 0.15)
					)
					(justify left bottom)
				)
			)
			(property "Value" "L_470n_1A_Coilcraft-PFL1609"
				(at 13.97 -2.54 0)
				(effects
					(font
						(size 1.27 1.27)
						(thickness 0.15)
					)
					(justify left bottom)
					(hide yes)
				)
			)
			(property "Footprint" "antmicro-footprints:L_Coilcraft-PFL1609"
				(at 13.97 -7.62 0)
				(effects
					(font
						(size 1.27 1.27)
						(thickness 0.15)
					)
					(justify left bottom)
					(hide yes)
				)
			)
			(property "Datasheet" "https://www.coilcraft.com/getmedia/2f4cd442-d64d-4413-a518-12fcfd03318d/pfl1609.pdf"
				(at 13.97 -10.16 0)
				(effects
					(font
						(size 1.27 1.27)
						(thickness 0.15)
					)
					(justify left bottom)
					(hide yes)
				)
			)
			(property "Description" "Power Inductor (SMT), 6.8 µH, 9.2 A, Shielded, 12.8 A, XAL7070"
				(at 0 0 0)
				(effects
					(font
						(size 1.27 1.27)
					)
					(hide yes)
				)
			)
			(property "Val" "470n/0.99A"
				(at 13.97 -5.08 0)
				(effects
					(font
						(size 1.27 1.27)
						(thickness 0.15)
					)
					(justify left bottom)
				)
			)
			(property "Manufacturer" "Coilcraft"
				(at 13.97 -12.7 0)
				(effects
					(font
						(size 1.27 1.27)
						(thickness 0.15)
					)
					(justify left bottom)
					(hide yes)
				)
			)
			(property "MPN" "PFL1609-471"
				(at 13.97 -15.24 0)
				(effects
					(font
						(size 1.27 1.27)
						(thickness 0.15)
					)
					(justify left bottom)
					(hide yes)
				)
			)
			(property "ISat" "0.99 A"
				(at 13.97 -16.51 0)
				(effects
					(font
						(size 1.27 1.27)
					)
					(justify left)
					(hide yes)
				)
			)
			(property "IMax" "1 A"
				(at 13.97 -20.32 0)
				(effects
					(font
						(size 1.27 1.27)
						(thickness 0.15)
					)
					(justify left bottom)
					(hide yes)
				)
			)
			(property "Size" "1.07x1.8"
				(at 13.97 -22.86 0)
				(effects
					(font
						(size 1.27 1.27)
						(thickness 0.15)
					)
					(justify left bottom)
					(hide yes)
				)
			)
			(property "Author" "Antmicro"
				(at 13.97 -25.4 0)
				(effects
					(font
						(size 1.27 1.27)
						(thickness 0.15)
					)
					(justify left bottom)
					(hide yes)
				)
			)
			(property "License" "Apache-2.0"
				(at 13.97 -27.94 0)
				(effects
					(font
						(size 1.27 1.27)
						(thickness 0.15)
					)
					(justify left bottom)
					(hide yes)
				)
			)
			(property "ki_keywords" "SMT, INDUCTOR, PASSIVE"
				(at 0 0 0)
				(effects
					(font
						(size 1.27 1.27)
					)
					(hide yes)
				)
			)
			(symbol "L_470n_1A_Coilcraft-PFL1609_0_1"
				(arc
					(start 0.508 0)
					(mid 1.016 0.5058)
					(end 1.524 0)
					(stroke
						(width 0)
						(type default)
					)
					(fill
						(type none)
					)
				)
				(arc
					(start 1.524 0)
					(mid 2.032 0.5058)
					(end 2.54 0)
					(stroke
						(width 0)
						(type default)
					)
					(fill
						(type none)
					)
				)
				(arc
					(start 2.54 0)
					(mid 3.048 0.5058)
					(end 3.556 0)
					(stroke
						(width 0)
						(type default)
					)
					(fill
						(type none)
					)
				)
				(arc
					(start 3.556 0)
					(mid 4.064 0.5058)
					(end 4.572 0)
					(stroke
						(width 0)
						(type default)
					)
					(fill
						(type none)
					)
				)
			)
			(symbol "L_470n_1A_Coilcraft-PFL1609_1_1"
				(pin passive line
					(at 0 0 0)
					(length 0.508)
					(name "~"
						(effects
							(font
								(size 1.27 1.27)
							)
						)
					)
					(number "1"
						(effects
							(font
								(size 1.27 1.27)
							)
						)
					)
				)
				(pin passive line
					(at 5.08 0 180)
					(length 0.508)
					(name "~"
						(effects
							(font
								(size 1.27 1.27)
							)
						)
					)
					(number "2"
						(effects
							(font
								(size 1.27 1.27)
							)
						)
					)
				)
			)
		)
	(symbol "antmicroFixedInductors:L_6u8_1A_Coilcraft-1210POC"
			(pin_numbers
				(hide yes)
			)
			(pin_names
				(hide yes)
			)
			(exclude_from_sim no)
			(in_bom yes)
			(on_board yes)
			(property "Reference" "L"
				(at 13.97 0 0)
				(effects
					(font
						(size 1.27 1.27)
						(thickness 0.15)
					)
					(justify left bottom)
				)
			)
			(property "Value" "L_6u8_1A_Coilcraft-1210POC"
				(at 13.97 -2.54 0)
				(effects
					(font
						(size 1.27 1.27)
						(thickness 0.15)
					)
					(justify left bottom)
					(hide yes)
				)
			)
			(property "Footprint" "antmicro-footprints:L_Coilcraft-1210POC"
				(at 13.97 -7.62 0)
				(effects
					(font
						(size 1.27 1.27)
						(thickness 0.15)
					)
					(justify left bottom)
					(hide yes)
				)
			)
			(property "Datasheet" "https://www.coilcraft.com/getmedia/5e8de018-68c5-4442-84ce-d5212c44660c/1210poc.pdf"
				(at 13.97 -10.16 0)
				(effects
					(font
						(size 1.27 1.27)
						(thickness 0.15)
					)
					(justify left bottom)
					(hide yes)
				)
			)
			(property "Description" "Power Inductor (SMT), 6.8 µH, 9.2 A, Shielded, 12.8 A, XAL7070"
				(at 0 0 0)
				(effects
					(font
						(size 1.27 1.27)
					)
					(hide yes)
				)
			)
			(property "Val" "6u8/1A"
				(at 13.97 -5.08 0)
				(effects
					(font
						(size 1.27 1.27)
						(thickness 0.15)
					)
					(justify left bottom)
				)
			)
			(property "Manufacturer" "Coilcraft"
				(at 13.97 -12.7 0)
				(effects
					(font
						(size 1.27 1.27)
						(thickness 0.15)
					)
					(justify left bottom)
					(hide yes)
				)
			)
			(property "MPN" "1210POC-682"
				(at 13.97 -15.24 0)
				(effects
					(font
						(size 1.27 1.27)
						(thickness 0.15)
					)
					(justify left bottom)
					(hide yes)
				)
			)
			(property "ISat" "1 A"
				(at 13.97 -16.51 0)
				(effects
					(font
						(size 1.27 1.27)
					)
					(justify left)
					(hide yes)
				)
			)
			(property "IMax" "1.36 A"
				(at 13.97 -20.32 0)
				(effects
					(font
						(size 1.27 1.27)
						(thickness 0.15)
					)
					(justify left bottom)
					(hide yes)
				)
			)
			(property "Size" "2.67x3.3"
				(at 13.97 -22.86 0)
				(effects
					(font
						(size 1.27 1.27)
						(thickness 0.15)
					)
					(justify left bottom)
					(hide yes)
				)
			)
			(property "Author" "Antmicro"
				(at 13.97 -25.4 0)
				(effects
					(font
						(size 1.27 1.27)
						(thickness 0.15)
					)
					(justify left bottom)
					(hide yes)
				)
			)
			(property "License" "Apache-2.0"
				(at 13.97 -27.94 0)
				(effects
					(font
						(size 1.27 1.27)
						(thickness 0.15)
					)
					(justify left bottom)
					(hide yes)
				)
			)
			(property "ki_keywords" "SMT, INDUCTOR, PASSIVE"
				(at 0 0 0)
				(effects
					(font
						(size 1.27 1.27)
					)
					(hide yes)
				)
			)
			(symbol "L_6u8_1A_Coilcraft-1210POC_0_1"
				(arc
					(start 0.508 0)
					(mid 1.016 0.5058)
					(end 1.524 0)
					(stroke
						(width 0)
						(type default)
					)
					(fill
						(type none)
					)
				)
				(arc
					(start 1.524 0)
					(mid 2.032 0.5058)
					(end 2.54 0)
					(stroke
						(width 0)
						(type default)
					)
					(fill
						(type none)
					)
				)
				(arc
					(start 2.54 0)
					(mid 3.048 0.5058)
					(end 3.556 0)
					(stroke
						(width 0)
						(type default)
					)
					(fill
						(type none)
					)
				)
				(arc
					(start 3.556 0)
					(mid 4.064 0.5058)
					(end 4.572 0)
					(stroke
						(width 0)
						(type default)
					)
					(fill
						(type none)
					)
				)
			)
			(symbol "L_6u8_1A_Coilcraft-1210POC_1_1"
				(pin passive line
					(at 0 0 0)
					(length 0.508)
					(name "~"
						(effects
							(font
								(size 1.27 1.27)
							)
						)
					)
					(number "1"
						(effects
							(font
								(size 1.27 1.27)
							)
						)
					)
				)
				(pin passive line
					(at 5.08 0 180)
					(length 0.508)
					(name "~"
						(effects
							(font
								(size 1.27 1.27)
							)
						)
					)
					(number "2"
						(effects
							(font
								(size 1.27 1.27)
							)
						)
					)
				)
			)
		)
	(symbol "antmicroFuses:F_4A_1206"
			(pin_numbers
				(hide yes)
			)
			(pin_names
				(offset 0.9906)
				(hide yes)
			)
			(exclude_from_sim no)
			(in_bom yes)
			(on_board yes)
			(property "Reference" "F"
				(at 20.32 -5.08 0)
				(effects
					(font
						(size 1.27 1.27)
						(thickness 0.15)
					)
					(justify left bottom)
				)
			)
			(property "Value" "F_4A_1206"
				(at 20.32 -7.62 0)
				(effects
					(font
						(size 1.27 1.27)
						(thickness 0.15)
					)
					(justify left bottom)
					(hide yes)
				)
			)
			(property "Footprint" "antmicro-footprints:F_1206_3216Metric"
				(at 20.32 -10.16 0)
				(effects
					(font
						(size 1.27 1.27)
						(thickness 0.15)
					)
					(justify left bottom)
					(hide yes)
				)
			)
			(property "Datasheet" "https://www.littelfuse.com/media?resourcetype=datasheets&itemid=dbe9bcd7-6072-4adf-bf5b-d33e52a6b90f&filename=littelfuse-fuse-466-datasheet"
				(at 20.32 -12.7 0)
				(effects
					(font
						(size 1.27 1.27)
						(thickness 0.15)
					)
					(justify left bottom)
					(hide yes)
				)
			)
			(property "Description" "Fuse, Surface Mount, 4 A, Very Fast Acting, 32 V, 32 V, 1206 (3216 Metric), 466"
				(at 0 0 0)
				(effects
					(font
						(size 1.27 1.27)
					)
					(hide yes)
				)
			)
			(property "Manufacturer" "Littelfuse"
				(at 20.32 -15.24 0)
				(effects
					(font
						(size 1.27 1.27)
						(thickness 0.15)
					)
					(justify left bottom)
					(hide yes)
				)
			)
			(property "MPN" "0466004.NR "
				(at 20.32 -17.78 0)
				(effects
					(font
						(size 1.27 1.27)
						(thickness 0.15)
					)
					(justify left bottom)
				)
			)
			(property "Author" "Antmicro"
				(at 20.32 -20.32 0)
				(effects
					(font
						(size 1.27 1.27)
						(thickness 0.15)
					)
					(justify left bottom)
					(hide yes)
				)
			)
			(property "License" "Apache-2.0"
				(at 20.32 -22.86 0)
				(effects
					(font
						(size 1.27 1.27)
						(thickness 0.15)
					)
					(justify left bottom)
					(hide yes)
				)
			)
			(property "ki_keywords" "FUSE, PASSIVE"
				(at 0 0 0)
				(effects
					(font
						(size 1.27 1.27)
					)
					(hide yes)
				)
			)
			(symbol "F_4A_1206_0_1"
				(rectangle
					(start 1.27 0.508)
					(end 3.81 -0.508)
					(stroke
						(width 0)
						(type default)
					)
					(fill
						(type none)
					)
				)
				(polyline
					(pts
						(xy 1.27 0) (xy 3.81 0)
					)
					(stroke
						(width 0)
						(type default)
					)
					(fill
						(type none)
					)
				)
			)
			(symbol "F_4A_1206_1_1"
				(pin passive line
					(at 0 0 0)
					(length 1.27)
					(name "~"
						(effects
							(font
								(size 1.27 1.27)
							)
						)
					)
					(number "1"
						(effects
							(font
								(size 1.27 1.27)
							)
						)
					)
				)
				(pin passive line
					(at 5.08 0 180)
					(length 1.27)
					(name "~"
						(effects
							(font
								(size 1.27 1.27)
							)
						)
					)
					(number "2"
						(effects
							(font
								(size 1.27 1.27)
							)
						)
					)
				)
			)
		)
	(symbol "antmicroInterfaceControllers:MAX96724GTN_VY+"
			(exclude_from_sim no)
			(in_bom yes)
			(on_board yes)
			(property "Reference" "U"
				(at 50.8 -2.54 0)
				(effects
					(font
						(size 1.27 1.27)
						(thickness 0.15)
					)
					(justify left bottom)
				)
			)
			(property "Value" "MAX96724GTN_VY+"
				(at 50.8 -7.62 0)
				(effects
					(font
						(size 1.27 1.27)
						(thickness 0.15)
					)
					(justify left bottom)
					(hide yes)
				)
			)
			(property "Footprint" "antmicro-footprints:QFN-56-1EP_8x8mm_P0.5mm_EP4.8x4.8mm"
				(at 50.8 -10.16 0)
				(effects
					(font
						(size 1.27 1.27)
						(thickness 0.15)
					)
					(justify left bottom)
					(hide yes)
				)
			)
			(property "Datasheet" "https://www.mouser.com/datasheet/2/609/max96724-3135154.pdf"
				(at 50.8 -12.7 0)
				(effects
					(font
						(size 1.27 1.27)
						(thickness 0.15)
					)
					(justify left bottom)
					(hide yes)
				)
			)
			(property "Description" "ADI GMSL2/1 Tunneling Quad Deserializer 6GHz with 2x4 or 4x2 MIPI DPHY/CPHY Outputs"
				(at 0 0 0)
				(effects
					(font
						(size 1.27 1.27)
					)
					(hide yes)
				)
			)
			(property "MPN" "MAX96724GTN/VY+"
				(at 50.8 -5.08 0)
				(effects
					(font
						(size 1.27 1.27)
						(thickness 0.15)
					)
					(justify left bottom)
				)
			)
			(property "Manufacturer" "Analog Devices"
				(at 50.8 -15.24 0)
				(effects
					(font
						(size 1.27 1.27)
						(thickness 0.15)
					)
					(justify left bottom)
					(hide yes)
				)
			)
			(property "Author" "Antmicro"
				(at 50.8 -17.78 0)
				(effects
					(font
						(size 1.27 1.27)
						(thickness 0.15)
					)
					(justify left bottom)
					(hide yes)
				)
			)
			(property "License" "Apache-2.0"
				(at 50.8 -20.32 0)
				(effects
					(font
						(size 1.27 1.27)
						(thickness 0.15)
					)
					(justify left bottom)
					(hide yes)
				)
			)
			(property "ki_keywords" "SMT, INTERFACE, IC, GMSL"
				(at 0 0 0)
				(effects
					(font
						(size 1.27 1.27)
					)
					(hide yes)
				)
			)
			(symbol "MAX96724GTN_VY+_1_1"
				(rectangle
					(start 2.54 2.54)
					(end 33.02 -88.9)
					(stroke
						(width 0.254)
						(type default)
					)
					(fill
						(type background)
					)
				)
				(polyline
					(pts
						(xy 21.59 -24.765) (xy 21.59 -48.895)
					)
					(stroke
						(width 0.254)
						(type default)
					)
					(fill
						(type background)
					)
				)
				(polyline
					(pts
						(xy 21.59 -24.765) (xy 22.225 -24.765)
					)
					(stroke
						(width 0.254)
						(type default)
					)
					(fill
						(type background)
					)
				)
				(polyline
					(pts
						(xy 21.59 -48.895) (xy 22.225 -48.895)
					)
					(stroke
						(width 0.254)
						(type default)
					)
					(fill
						(type background)
					)
				)
				(polyline
					(pts
						(xy 21.59 -62.865) (xy 21.59 -86.995)
					)
					(stroke
						(width 0.254)
						(type default)
					)
					(fill
						(type background)
					)
				)
				(polyline
					(pts
						(xy 21.59 -62.865) (xy 22.225 -62.865)
					)
					(stroke
						(width 0.254)
						(type default)
					)
					(fill
						(type background)
					)
				)
				(polyline
					(pts
						(xy 21.59 -86.995) (xy 22.225 -86.995)
					)
					(stroke
						(width 0.254)
						(type default)
					)
					(fill
						(type background)
					)
				)
				(polyline
					(pts
						(xy 24.765 -19.685) (xy 24.765 -33.655)
					)
					(stroke
						(width 0.254)
						(type default)
					)
					(fill
						(type background)
					)
				)
				(polyline
					(pts
						(xy 24.765 -19.685) (xy 25.4 -19.685)
					)
					(stroke
						(width 0.254)
						(type default)
					)
					(fill
						(type background)
					)
				)
				(polyline
					(pts
						(xy 24.765 -33.655) (xy 25.4 -33.655)
					)
					(stroke
						(width 0.254)
						(type default)
					)
					(fill
						(type background)
					)
				)
				(polyline
					(pts
						(xy 24.765 -34.925) (xy 24.765 -48.895)
					)
					(stroke
						(width 0.254)
						(type default)
					)
					(fill
						(type background)
					)
				)
				(polyline
					(pts
						(xy 24.765 -34.925) (xy 25.4 -34.925)
					)
					(stroke
						(width 0.254)
						(type default)
					)
					(fill
						(type background)
					)
				)
				(polyline
					(pts
						(xy 24.765 -48.895) (xy 25.4 -48.895)
					)
					(stroke
						(width 0.254)
						(type default)
					)
					(fill
						(type background)
					)
				)
				(polyline
					(pts
						(xy 24.765 -57.785) (xy 24.765 -71.755)
					)
					(stroke
						(width 0.254)
						(type default)
					)
					(fill
						(type background)
					)
				)
				(polyline
					(pts
						(xy 24.765 -57.785) (xy 25.4 -57.785)
					)
					(stroke
						(width 0.254)
						(type default)
					)
					(fill
						(type background)
					)
				)
				(polyline
					(pts
						(xy 24.765 -71.755) (xy 25.4 -71.755)
					)
					(stroke
						(width 0.254)
						(type default)
					)
					(fill
						(type background)
					)
				)
				(polyline
					(pts
						(xy 24.765 -73.025) (xy 24.765 -86.995)
					)
					(stroke
						(width 0.254)
						(type default)
					)
					(fill
						(type background)
					)
				)
				(polyline
					(pts
						(xy 24.765 -73.025) (xy 25.4 -73.025)
					)
					(stroke
						(width 0.254)
						(type default)
					)
					(fill
						(type background)
					)
				)
				(polyline
					(pts
						(xy 24.765 -86.995) (xy 25.4 -86.995)
					)
					(stroke
						(width 0.254)
						(type default)
					)
					(fill
						(type background)
					)
				)
				(text "1.2/1.0V"
					(at 7.112 -3.556 0)
					(effects
						(font
							(size 1.27 1.27)
							(thickness 0.15)
						)
						(justify left bottom)
					)
				)
				(text "1.8/3.3V"
					(at 17.78 -1.016 0)
					(effects
						(font
							(size 1.27 1.27)
							(thickness 0.15)
						)
						(justify left bottom)
					)
				)
				(text "1.2V"
					(at 21.082 -6.096 0)
					(effects
						(font
							(size 1.27 1.27)
							(thickness 0.15)
						)
						(justify left bottom)
					)
				)
				(text "4-lane"
					(at 21.59 -40.005 900)
					(effects
						(font
							(size 1.27 1.27)
							(thickness 0.15)
						)
						(justify left bottom)
					)
				)
				(text "4-lane"
					(at 21.59 -78.74 900)
					(effects
						(font
							(size 1.27 1.27)
							(thickness 0.15)
						)
						(justify left bottom)
					)
				)
				(text "2-lane"
					(at 24.765 -31.115 900)
					(effects
						(font
							(size 1.27 1.27)
							(thickness 0.15)
						)
						(justify left bottom)
					)
				)
				(text "2-lane"
					(at 24.765 -45.085 900)
					(effects
						(font
							(size 1.27 1.27)
							(thickness 0.15)
						)
						(justify left bottom)
					)
				)
				(text "2-lane"
					(at 24.765 -68.58 900)
					(effects
						(font
							(size 1.27 1.27)
							(thickness 0.15)
						)
						(justify left bottom)
					)
				)
				(text "2-lane"
					(at 24.765 -83.82 900)
					(effects
						(font
							(size 1.27 1.27)
							(thickness 0.15)
						)
						(justify left bottom)
					)
				)
				(pin passive line
					(at 0 0 0)
					(length 2.54)
					(name "VDD_1.8V"
						(effects
							(font
								(size 1.27 1.27)
							)
						)
					)
					(number "21"
						(effects
							(font
								(size 1.27 1.27)
							)
						)
					)
				)
				(pin passive line
					(at 0 0 0)
					(length 2.54)
					(hide yes)
					(name "VDD_1.8V"
						(effects
							(font
								(size 1.27 1.27)
							)
						)
					)
					(number "7"
						(effects
							(font
								(size 1.27 1.27)
							)
						)
					)
				)
				(pin passive line
					(at 0 -2.54 0)
					(length 2.54)
					(name "VDD"
						(effects
							(font
								(size 1.27 1.27)
							)
						)
					)
					(number "55"
						(effects
							(font
								(size 1.27 1.27)
							)
						)
					)
				)
				(pin passive line
					(at 0 -2.54 0)
					(length 2.54)
					(hide yes)
					(name "VDD"
						(effects
							(font
								(size 1.27 1.27)
							)
						)
					)
					(number "56"
						(effects
							(font
								(size 1.27 1.27)
							)
						)
					)
				)
				(pin passive line
					(at 0 -12.7 0)
					(length 2.54)
					(name "SIOA_P"
						(effects
							(font
								(size 1.27 1.27)
							)
						)
					)
					(number "23"
						(effects
							(font
								(size 1.27 1.27)
							)
						)
					)
				)
				(pin passive line
					(at 0 -15.24 0)
					(length 2.54)
					(name "SIOA_N"
						(effects
							(font
								(size 1.27 1.27)
							)
						)
					)
					(number "22"
						(effects
							(font
								(size 1.27 1.27)
							)
						)
					)
				)
				(pin passive line
					(at 0 -20.32 0)
					(length 2.54)
					(name "SIOB_P"
						(effects
							(font
								(size 1.27 1.27)
							)
						)
					)
					(number "18"
						(effects
							(font
								(size 1.27 1.27)
							)
						)
					)
				)
				(pin passive line
					(at 0 -22.86 0)
					(length 2.54)
					(name "SIOB_N"
						(effects
							(font
								(size 1.27 1.27)
							)
						)
					)
					(number "19"
						(effects
							(font
								(size 1.27 1.27)
							)
						)
					)
				)
				(pin passive line
					(at 0 -27.94 0)
					(length 2.54)
					(name "SIOC_P"
						(effects
							(font
								(size 1.27 1.27)
							)
						)
					)
					(number "10"
						(effects
							(font
								(size 1.27 1.27)
							)
						)
					)
				)
				(pin passive line
					(at 0 -30.48 0)
					(length 2.54)
					(name "SIOC_N"
						(effects
							(font
								(size 1.27 1.27)
							)
						)
					)
					(number "9"
						(effects
							(font
								(size 1.27 1.27)
							)
						)
					)
				)
				(pin passive line
					(at 0 -35.56 0)
					(length 2.54)
					(name "SIOD_P"
						(effects
							(font
								(size 1.27 1.27)
							)
						)
					)
					(number "5"
						(effects
							(font
								(size 1.27 1.27)
							)
						)
					)
				)
				(pin passive line
					(at 0 -38.1 0)
					(length 2.54)
					(name "SIOD_N"
						(effects
							(font
								(size 1.27 1.27)
							)
						)
					)
					(number "6"
						(effects
							(font
								(size 1.27 1.27)
							)
						)
					)
				)
				(pin passive line
					(at 0 -45.72 0)
					(length 2.54)
					(name "CFG0"
						(effects
							(font
								(size 1.27 1.27)
							)
						)
					)
					(number "4"
						(effects
							(font
								(size 1.27 1.27)
							)
						)
					)
				)
				(pin passive line
					(at 0 -48.26 0)
					(length 2.54)
					(name "MFP0"
						(effects
							(font
								(size 1.27 1.27)
							)
						)
					)
					(number "1"
						(effects
							(font
								(size 1.27 1.27)
							)
						)
					)
				)
				(pin passive line
					(at 0 -50.8 0)
					(length 2.54)
					(name "MFP1"
						(effects
							(font
								(size 1.27 1.27)
							)
						)
					)
					(number "2"
						(effects
							(font
								(size 1.27 1.27)
							)
						)
					)
				)
				(pin passive line
					(at 0 -53.34 0)
					(length 2.54)
					(name "MFP2"
						(effects
							(font
								(size 1.27 1.27)
							)
						)
					)
					(number "3"
						(effects
							(font
								(size 1.27 1.27)
							)
						)
					)
				)
				(pin passive line
					(at 0 -55.88 0)
					(length 2.54)
					(name "MFP3"
						(effects
							(font
								(size 1.27 1.27)
							)
						)
					)
					(number "12"
						(effects
							(font
								(size 1.27 1.27)
							)
						)
					)
				)
				(pin passive line
					(at 0 -58.42 0)
					(length 2.54)
					(name "MFP4"
						(effects
							(font
								(size 1.27 1.27)
							)
						)
					)
					(number "13"
						(effects
							(font
								(size 1.27 1.27)
							)
						)
					)
				)
				(pin passive line
					(at 0 -60.96 0)
					(length 2.54)
					(name "MFP5"
						(effects
							(font
								(size 1.27 1.27)
							)
						)
					)
					(number "14"
						(effects
							(font
								(size 1.27 1.27)
							)
						)
					)
				)
				(pin passive line
					(at 0 -63.5 0)
					(length 2.54)
					(name "CFG1/MFP6"
						(effects
							(font
								(size 1.27 1.27)
							)
						)
					)
					(number "25"
						(effects
							(font
								(size 1.27 1.27)
							)
						)
					)
				)
				(pin passive line
					(at 0 -66.04 0)
					(length 2.54)
					(name "SDA1/MFP7"
						(effects
							(font
								(size 1.27 1.27)
							)
						)
					)
					(number "26"
						(effects
							(font
								(size 1.27 1.27)
							)
						)
					)
				)
				(pin passive line
					(at 0 -68.58 0)
					(length 2.54)
					(name "SCL1/MFP8"
						(effects
							(font
								(size 1.27 1.27)
							)
						)
					)
					(number "27"
						(effects
							(font
								(size 1.27 1.27)
							)
						)
					)
				)
				(pin passive line
					(at 0 -73.66 0)
					(length 2.54)
					(name "X1/OSC"
						(effects
							(font
								(size 1.27 1.27)
							)
						)
					)
					(number "15"
						(effects
							(font
								(size 1.27 1.27)
							)
						)
					)
				)
				(pin passive line
					(at 0 -76.2 0)
					(length 2.54)
					(name "X2"
						(effects
							(font
								(size 1.27 1.27)
							)
						)
					)
					(number "16"
						(effects
							(font
								(size 1.27 1.27)
							)
						)
					)
				)
				(pin passive line
					(at 0 -81.28 0)
					(length 2.54)
					(name "CAP_VDD"
						(effects
							(font
								(size 1.27 1.27)
							)
						)
					)
					(number "20"
						(effects
							(font
								(size 1.27 1.27)
							)
						)
					)
				)
				(pin passive line
					(at 0 -81.28 0)
					(length 2.54)
					(hide yes)
					(name "CAP_VDD"
						(effects
							(font
								(size 1.27 1.27)
							)
						)
					)
					(number "8"
						(effects
							(font
								(size 1.27 1.27)
							)
						)
					)
				)
				(pin passive line
					(at 0 -83.82 0)
					(length 2.54)
					(name "XRES"
						(effects
							(font
								(size 1.27 1.27)
							)
						)
					)
					(number "17"
						(effects
							(font
								(size 1.27 1.27)
							)
						)
					)
				)
				(pin passive line
					(at 0 -86.36 0)
					(length 2.54)
					(name "GND"
						(effects
							(font
								(size 1.27 1.27)
							)
						)
					)
					(number "57"
						(effects
							(font
								(size 1.27 1.27)
							)
						)
					)
				)
				(pin passive line
					(at 35.56 0 180)
					(length 2.54)
					(name "VDDIO"
						(effects
							(font
								(size 1.27 1.27)
							)
						)
					)
					(number "24"
						(effects
							(font
								(size 1.27 1.27)
							)
						)
					)
				)
				(pin passive line
					(at 35.56 -2.54 180)
					(length 2.54)
					(name "PWDNB"
						(effects
							(font
								(size 1.27 1.27)
							)
						)
					)
					(number "11"
						(effects
							(font
								(size 1.27 1.27)
							)
						)
					)
				)
				(pin passive line
					(at 35.56 -5.08 180)
					(length 2.54)
					(name "VTERM"
						(effects
							(font
								(size 1.27 1.27)
							)
						)
					)
					(number "30"
						(effects
							(font
								(size 1.27 1.27)
							)
						)
					)
				)
				(pin passive line
					(at 35.56 -10.16 180)
					(length 2.54)
					(name "SCL"
						(effects
							(font
								(size 1.27 1.27)
							)
						)
					)
					(number "29"
						(effects
							(font
								(size 1.27 1.27)
							)
						)
					)
				)
				(pin passive line
					(at 35.56 -12.7 180)
					(length 2.54)
					(name "SDA"
						(effects
							(font
								(size 1.27 1.27)
							)
						)
					)
					(number "28"
						(effects
							(font
								(size 1.27 1.27)
							)
						)
					)
				)
				(pin passive line
					(at 35.56 -20.32 180)
					(length 2.54)
					(name "CKC_P"
						(effects
							(font
								(size 1.27 1.27)
							)
						)
					)
					(number "33"
						(effects
							(font
								(size 1.27 1.27)
							)
						)
					)
				)
				(pin passive line
					(at 35.56 -22.86 180)
					(length 2.54)
					(name "CKC_N"
						(effects
							(font
								(size 1.27 1.27)
							)
						)
					)
					(number "34"
						(effects
							(font
								(size 1.27 1.27)
							)
						)
					)
				)
				(pin passive line
					(at 35.56 -25.4 180)
					(length 2.54)
					(name "DA0_P"
						(effects
							(font
								(size 1.27 1.27)
							)
						)
					)
					(number "31"
						(effects
							(font
								(size 1.27 1.27)
							)
						)
					)
				)
				(pin passive line
					(at 35.56 -27.94 180)
					(length 2.54)
					(name "DA0_N"
						(effects
							(font
								(size 1.27 1.27)
							)
						)
					)
					(number "32"
						(effects
							(font
								(size 1.27 1.27)
							)
						)
					)
				)
				(pin passive line
					(at 35.56 -30.48 180)
					(length 2.54)
					(name "DA1_P"
						(effects
							(font
								(size 1.27 1.27)
							)
						)
					)
					(number "35"
						(effects
							(font
								(size 1.27 1.27)
							)
						)
					)
				)
				(pin passive line
					(at 35.56 -33.02 180)
					(length 2.54)
					(name "DA1_N"
						(effects
							(font
								(size 1.27 1.27)
							)
						)
					)
					(number "36"
						(effects
							(font
								(size 1.27 1.27)
							)
						)
					)
				)
				(pin passive line
					(at 35.56 -35.56 180)
					(length 2.54)
					(name "DA2_P"
						(effects
							(font
								(size 1.27 1.27)
							)
						)
					)
					(number "37"
						(effects
							(font
								(size 1.27 1.27)
							)
						)
					)
				)
				(pin passive line
					(at 35.56 -38.1 180)
					(length 2.54)
					(name "DA2_N"
						(effects
							(font
								(size 1.27 1.27)
							)
						)
					)
					(number "38"
						(effects
							(font
								(size 1.27 1.27)
							)
						)
					)
				)
				(pin passive line
					(at 35.56 -40.64 180)
					(length 2.54)
					(name "DA3_P"
						(effects
							(font
								(size 1.27 1.27)
							)
						)
					)
					(number "41"
						(effects
							(font
								(size 1.27 1.27)
							)
						)
					)
				)
				(pin passive line
					(at 35.56 -43.18 180)
					(length 2.54)
					(name "DA3_N"
						(effects
							(font
								(size 1.27 1.27)
							)
						)
					)
					(number "42"
						(effects
							(font
								(size 1.27 1.27)
							)
						)
					)
				)
				(pin passive line
					(at 35.56 -45.72 180)
					(length 2.54)
					(name "CKA_P"
						(effects
							(font
								(size 1.27 1.27)
							)
						)
					)
					(number "39"
						(effects
							(font
								(size 1.27 1.27)
							)
						)
					)
				)
				(pin passive line
					(at 35.56 -48.26 180)
					(length 2.54)
					(name "CKA_N"
						(effects
							(font
								(size 1.27 1.27)
							)
						)
					)
					(number "40"
						(effects
							(font
								(size 1.27 1.27)
							)
						)
					)
				)
				(pin passive line
					(at 35.56 -58.42 180)
					(length 2.54)
					(name "CKF_P"
						(effects
							(font
								(size 1.27 1.27)
							)
						)
					)
					(number "51"
						(effects
							(font
								(size 1.27 1.27)
							)
						)
					)
				)
				(pin passive line
					(at 35.56 -60.96 180)
					(length 2.54)
					(name "CKF_N"
						(effects
							(font
								(size 1.27 1.27)
							)
						)
					)
					(number "52"
						(effects
							(font
								(size 1.27 1.27)
							)
						)
					)
				)
				(pin passive line
					(at 35.56 -63.5 180)
					(length 2.54)
					(name "DB0_P"
						(effects
							(font
								(size 1.27 1.27)
							)
						)
					)
					(number "43"
						(effects
							(font
								(size 1.27 1.27)
							)
						)
					)
				)
				(pin passive line
					(at 35.56 -66.04 180)
					(length 2.54)
					(name "DB0_N"
						(effects
							(font
								(size 1.27 1.27)
							)
						)
					)
					(number "44"
						(effects
							(font
								(size 1.27 1.27)
							)
						)
					)
				)
				(pin passive line
					(at 35.56 -68.58 180)
					(length 2.54)
					(name "DB1_P"
						(effects
							(font
								(size 1.27 1.27)
							)
						)
					)
					(number "47"
						(effects
							(font
								(size 1.27 1.27)
							)
						)
					)
				)
				(pin passive line
					(at 35.56 -71.12 180)
					(length 2.54)
					(name "DB1_N"
						(effects
							(font
								(size 1.27 1.27)
							)
						)
					)
					(number "48"
						(effects
							(font
								(size 1.27 1.27)
							)
						)
					)
				)
				(pin passive line
					(at 35.56 -73.66 180)
					(length 2.54)
					(name "DB2_P"
						(effects
							(font
								(size 1.27 1.27)
							)
						)
					)
					(number "49"
						(effects
							(font
								(size 1.27 1.27)
							)
						)
					)
				)
				(pin passive line
					(at 35.56 -76.2 180)
					(length 2.54)
					(name "DB2_N"
						(effects
							(font
								(size 1.27 1.27)
							)
						)
					)
					(number "50"
						(effects
							(font
								(size 1.27 1.27)
							)
						)
					)
				)
				(pin passive line
					(at 35.56 -78.74 180)
					(length 2.54)
					(name "DB3_P"
						(effects
							(font
								(size 1.27 1.27)
							)
						)
					)
					(number "53"
						(effects
							(font
								(size 1.27 1.27)
							)
						)
					)
				)
				(pin passive line
					(at 35.56 -81.28 180)
					(length 2.54)
					(name "DB3_N"
						(effects
							(font
								(size 1.27 1.27)
							)
						)
					)
					(number "54"
						(effects
							(font
								(size 1.27 1.27)
							)
						)
					)
				)
				(pin passive line
					(at 35.56 -83.82 180)
					(length 2.54)
					(name "CKB_P"
						(effects
							(font
								(size 1.27 1.27)
							)
						)
					)
					(number "45"
						(effects
							(font
								(size 1.27 1.27)
							)
						)
					)
				)
				(pin passive line
					(at 35.56 -86.36 180)
					(length 2.54)
					(name "CKB_N"
						(effects
							(font
								(size 1.27 1.27)
							)
						)
					)
					(number "46"
						(effects
							(font
								(size 1.27 1.27)
							)
						)
					)
				)
			)
		)
	(symbol "antmicroLEDIndicationDiscrete:LED_G_0603_LTST-C190GKT"
			(pin_numbers
				(hide yes)
			)
			(pin_names
				(hide yes)
			)
			(exclude_from_sim no)
			(in_bom yes)
			(on_board yes)
			(property "Reference" "D"
				(at 22.86 -2.54 0)
				(effects
					(font
						(size 1.27 1.27)
						(thickness 0.15)
					)
					(justify left bottom)
				)
			)
			(property "Value" "LED_G_0603_LTST-C190GKT"
				(at 22.86 -7.62 0)
				(effects
					(font
						(size 1.27 1.27)
						(thickness 0.15)
					)
					(justify left bottom)
					(hide yes)
				)
			)
			(property "Footprint" "antmicro-footprints:LED_0603_1608Metric_G"
				(at 22.86 -10.16 0)
				(effects
					(font
						(size 1.27 1.27)
						(thickness 0.15)
					)
					(justify left bottom)
					(hide yes)
				)
			)
			(property "Datasheet" "https://media.digikey.com/pdf/Data%20Sheets/Lite-On%20PDFs/LTST-C190GKT.pdf"
				(at 22.86 -12.7 0)
				(effects
					(font
						(size 1.27 1.27)
						(thickness 0.15)
					)
					(justify left bottom)
					(hide yes)
				)
			)
			(property "Description" "LED, Green, SMD, 0603, 20 mA, 2.1 V, 569 nm"
				(at 0 0 0)
				(effects
					(font
						(size 1.27 1.27)
					)
					(hide yes)
				)
			)
			(property "MPN" "LTST-C190GKT"
				(at 22.86 -15.24 0)
				(effects
					(font
						(size 1.27 1.27)
						(thickness 0.15)
					)
					(justify left bottom)
					(hide yes)
				)
			)
			(property "Manufacturer" "Lite-On"
				(at 22.86 -17.78 0)
				(effects
					(font
						(size 1.27 1.27)
						(thickness 0.15)
					)
					(justify left bottom)
					(hide yes)
				)
			)
			(property "Color" "Green"
				(at 22.86 -5.08 0)
				(effects
					(font
						(size 1.27 1.27)
					)
					(justify left bottom)
				)
			)
			(property "Author" "Antmicro"
				(at 22.86 -20.32 0)
				(effects
					(font
						(size 1.27 1.27)
						(thickness 0.15)
					)
					(justify left bottom)
					(hide yes)
				)
			)
			(property "License" "Apache-2.0"
				(at 22.86 -22.86 0)
				(effects
					(font
						(size 1.27 1.27)
						(thickness 0.15)
					)
					(justify left bottom)
					(hide yes)
				)
			)
			(property "ki_keywords" "SMT, DIODE, SEMICONDUCTOR, LED"
				(at 0 0 0)
				(effects
					(font
						(size 1.27 1.27)
					)
					(hide yes)
				)
			)
			(symbol "LED_G_0603_LTST-C190GKT_0_1"
				(polyline
					(pts
						(xy 1.905 0) (xy 0.635 0)
					)
					(stroke
						(width 0)
						(type default)
					)
					(fill
						(type none)
					)
				)
				(polyline
					(pts
						(xy 4.445 0) (xy 3.175 0)
					)
					(stroke
						(width 0)
						(type default)
					)
					(fill
						(type none)
					)
				)
			)
			(symbol "LED_G_0603_LTST-C190GKT_1_1"
				(polyline
					(pts
						(xy 1.143 2.286) (xy 1.143 1.778) (xy 1.143 2.286) (xy 1.651 2.286) (xy 1.143 2.286) (xy 2.159 1.27)
					)
					(stroke
						(width 0.254)
						(type default)
					)
					(fill
						(type none)
					)
				)
				(polyline
					(pts
						(xy 1.778 1.016) (xy 1.778 -1.016)
					)
					(stroke
						(width 0.254)
						(type default)
					)
					(fill
						(type none)
					)
				)
				(polyline
					(pts
						(xy 2.159 2.54) (xy 2.159 2.032) (xy 2.159 2.54) (xy 2.667 2.54) (xy 2.159 2.54) (xy 3.048 1.651)
					)
					(stroke
						(width 0.254)
						(type default)
					)
					(fill
						(type none)
					)
				)
				(polyline
					(pts
						(xy 3.302 1.016) (xy 3.302 -1.016) (xy 1.778 0) (xy 3.302 1.016)
					)
					(stroke
						(width 0.254)
						(type default)
					)
					(fill
						(type outline)
					)
				)
				(pin passive line
					(at 0 0 0)
					(length 0.635)
					(name "C"
						(effects
							(font
								(size 1.27 1.27)
							)
						)
					)
					(number "1"
						(effects
							(font
								(size 1.27 1.27)
							)
						)
					)
				)
				(pin passive line
					(at 5.08 0 180)
					(length 0.635)
					(name "A"
						(effects
							(font
								(size 1.27 1.27)
							)
						)
					)
					(number "2"
						(effects
							(font
								(size 1.27 1.27)
							)
						)
					)
				)
			)
		)
	(symbol "antmicroLogicBuffersDriversReceiversTransceivers:SN74LV1T125DBVR"
			(exclude_from_sim no)
			(in_bom yes)
			(on_board yes)
			(property "Reference" "U"
				(at 27.94 -5.08 0)
				(effects
					(font
						(size 1.27 1.27)
						(thickness 0.15)
					)
					(justify left bottom)
				)
			)
			(property "Value" "SN74LV1T125DBVR"
				(at 27.94 -7.62 0)
				(effects
					(font
						(size 1.27 1.27)
						(thickness 0.15)
					)
					(justify left bottom)
					(hide yes)
				)
			)
			(property "Footprint" "antmicro-footprints:SOT-23-5"
				(at 27.94 -10.16 0)
				(effects
					(font
						(size 1.27 1.27)
						(thickness 0.15)
					)
					(justify left bottom)
					(hide yes)
				)
			)
			(property "Datasheet" "https://www.ti.com/lit/ds/symlink/sn74lv1t125.pdf?HQS=dis-mous-null-mousermode-dsf-pf-null-wwe&ts=1627648952184&ref_url=https%253A%252F%252Fmouser.com%252F"
				(at 27.94 -12.7 0)
				(effects
					(font
						(size 1.27 1.27)
						(thickness 0.15)
					)
					(justify left bottom)
					(hide yes)
				)
			)
			(property "Description" "Buffer, 74LV1T125, 1.6 V to 5.5 V, SOT-23-5"
				(at 0 0 0)
				(effects
					(font
						(size 1.27 1.27)
					)
					(hide yes)
				)
			)
			(property "MPN" "SN74LV1T125DBVR"
				(at 27.94 -15.24 0)
				(effects
					(font
						(size 1.27 1.27)
						(thickness 0.15)
					)
					(justify left bottom)
				)
			)
			(property "Manufacturer" "Texas Instruments"
				(at 27.94 -17.78 0)
				(effects
					(font
						(size 1.27 1.27)
						(thickness 0.15)
					)
					(justify left bottom)
					(hide yes)
				)
			)
			(property "Author" "Antmicro"
				(at 27.94 -20.32 0)
				(effects
					(font
						(size 1.27 1.27)
						(thickness 0.15)
					)
					(justify left bottom)
					(hide yes)
				)
			)
			(property "License" "Apache-2.0"
				(at 27.94 -22.86 0)
				(effects
					(font
						(size 1.27 1.27)
						(thickness 0.15)
					)
					(justify left bottom)
					(hide yes)
				)
			)
			(property "ki_keywords" "SMT, LOGIC, IC, BUFFER, TRANSCEIVER, LEVEL-SHIFTER, GATE"
				(at 0 0 0)
				(effects
					(font
						(size 1.27 1.27)
					)
					(hide yes)
				)
			)
			(symbol "SN74LV1T125DBVR_1_1"
				(rectangle
					(start 2.54 2.54)
					(end 11.43 -9.525)
					(stroke
						(width 0.254)
						(type default)
					)
					(fill
						(type background)
					)
				)
				(polyline
					(pts
						(xy 5.08 -2.54) (xy 5.08 -5.08) (xy 7.62 -3.81) (xy 5.08 -2.54)
					)
					(stroke
						(width 0.254)
						(type default)
					)
					(fill
						(type background)
					)
				)
				(polyline
					(pts
						(xy 5.08 -3.81) (xy 4.318 -3.81) (xy 4.572 -3.81)
					)
					(stroke
						(width 0.254)
						(type default)
					)
					(fill
						(type background)
					)
				)
				(polyline
					(pts
						(xy 5.715 0) (xy 6.35 0) (xy 6.35 -1.27)
					)
					(stroke
						(width 0.254)
						(type default)
					)
					(fill
						(type background)
					)
				)
				(polyline
					(pts
						(xy 6.35 -1.27) (xy 6.35 -2.54)
					)
					(stroke
						(width 0.254)
						(type default)
					)
					(fill
						(type background)
					)
				)
				(circle
					(center 6.35 -2.794)
					(radius 0.254)
					(stroke
						(width 0.254)
						(type default)
					)
					(fill
						(type background)
					)
				)
				(polyline
					(pts
						(xy 7.62 -3.81) (xy 9.652 -3.81)
					)
					(stroke
						(width 0.254)
						(type default)
					)
					(fill
						(type background)
					)
				)
				(pin input line
					(at 0 0 0)
					(length 2.54)
					(name "~{OE}"
						(effects
							(font
								(size 1.27 1.27)
							)
						)
					)
					(number "1"
						(effects
							(font
								(size 1.27 1.27)
							)
						)
					)
				)
				(pin input line
					(at 0 -3.81 0)
					(length 2.54)
					(name "A"
						(effects
							(font
								(size 1.27 1.27)
							)
						)
					)
					(number "2"
						(effects
							(font
								(size 1.27 1.27)
							)
						)
					)
				)
				(pin power_in line
					(at 13.97 0 180)
					(length 2.54)
					(name "VCC"
						(effects
							(font
								(size 1.27 1.27)
							)
						)
					)
					(number "5"
						(effects
							(font
								(size 1.27 1.27)
							)
						)
					)
				)
				(pin output line
					(at 13.97 -3.81 180)
					(length 2.54)
					(name "Y"
						(effects
							(font
								(size 1.27 1.27)
							)
						)
					)
					(number "4"
						(effects
							(font
								(size 1.27 1.27)
							)
						)
					)
				)
				(pin power_in line
					(at 13.97 -7.62 180)
					(length 2.54)
					(name "GND"
						(effects
							(font
								(size 1.27 1.27)
							)
						)
					)
					(number "3"
						(effects
							(font
								(size 1.27 1.27)
							)
						)
					)
				)
			)
		)
	(symbol "antmicroLogicTranslatorsLevelShifters:NTS0102_TSSOP"
			(exclude_from_sim no)
			(in_bom yes)
			(on_board yes)
			(property "Reference" "U"
				(at 35.56 -3.81 0)
				(effects
					(font
						(size 1.27 1.27)
						(thickness 0.15)
					)
					(justify left bottom)
				)
			)
			(property "Value" "NTS0102_TSSOP"
				(at 35.56 -6.35 0)
				(effects
					(font
						(size 1.27 1.27)
						(thickness 0.15)
					)
					(justify left bottom)
					(hide yes)
				)
			)
			(property "Footprint" "antmicro-footprints:TSSOP-8_3x3mm_P0.65mm"
				(at 35.56 -8.89 0)
				(effects
					(font
						(size 1.27 1.27)
						(thickness 0.15)
					)
					(justify left bottom)
					(hide yes)
				)
			)
			(property "Datasheet" "https://www.mouser.com/datasheet/2/302/NTS0102-1127324.pdf"
				(at 35.56 -11.43 0)
				(effects
					(font
						(size 1.27 1.27)
						(thickness 0.15)
					)
					(justify left bottom)
					(hide yes)
				)
			)
			(property "Description" "Transceiver, 1.65 V to 3.6 V, TSSOP-8"
				(at 0 0 0)
				(effects
					(font
						(size 1.27 1.27)
					)
					(hide yes)
				)
			)
			(property "MPN" "NTS0102DP"
				(at 35.56 -13.97 0)
				(effects
					(font
						(size 1.27 1.27)
						(thickness 0.15)
					)
					(justify left bottom)
				)
			)
			(property "Manufacturer" "NXP"
				(at 35.56 -16.51 0)
				(effects
					(font
						(size 1.27 1.27)
						(thickness 0.15)
					)
					(justify left bottom)
					(hide yes)
				)
			)
			(property "Author" "Antmicro"
				(at 35.56 -19.05 0)
				(effects
					(font
						(size 1.27 1.27)
						(thickness 0.15)
					)
					(justify left bottom)
					(hide yes)
				)
			)
			(property "License" "Apache-2.0"
				(at 35.56 -21.59 0)
				(effects
					(font
						(size 1.27 1.27)
						(thickness 0.15)
					)
					(justify left bottom)
					(hide yes)
				)
			)
			(property "ki_keywords" "SMT, LEVEL-SHIFTER, IC, LOGIC"
				(at 0 0 0)
				(effects
					(font
						(size 1.27 1.27)
					)
					(hide yes)
				)
			)
			(symbol "NTS0102_TSSOP_1_1"
				(rectangle
					(start 2.54 2.54)
					(end 17.78 -10.16)
					(stroke
						(width 0.254)
						(type default)
					)
					(fill
						(type background)
					)
				)
				(pin power_in line
					(at 0 0 0)
					(length 2.54)
					(name "VCC_{A}"
						(effects
							(font
								(size 1.27 1.27)
							)
						)
					)
					(number "3"
						(effects
							(font
								(size 1.27 1.27)
							)
						)
					)
				)
				(pin bidirectional line
					(at 0 -2.54 0)
					(length 2.54)
					(name "A_{1}"
						(effects
							(font
								(size 1.27 1.27)
							)
						)
					)
					(number "5"
						(effects
							(font
								(size 1.27 1.27)
							)
						)
					)
				)
				(pin bidirectional line
					(at 0 -5.08 0)
					(length 2.54)
					(name "A_{2}"
						(effects
							(font
								(size 1.27 1.27)
							)
						)
					)
					(number "4"
						(effects
							(font
								(size 1.27 1.27)
							)
						)
					)
				)
				(pin input line
					(at 0 -7.62 0)
					(length 2.54)
					(name "OE"
						(effects
							(font
								(size 1.27 1.27)
							)
						)
					)
					(number "6"
						(effects
							(font
								(size 1.27 1.27)
							)
						)
					)
				)
				(pin power_in line
					(at 20.32 0 180)
					(length 2.54)
					(name "VCC_{B}"
						(effects
							(font
								(size 1.27 1.27)
							)
						)
					)
					(number "7"
						(effects
							(font
								(size 1.27 1.27)
							)
						)
					)
				)
				(pin bidirectional line
					(at 20.32 -2.54 180)
					(length 2.54)
					(name "B_{1}"
						(effects
							(font
								(size 1.27 1.27)
							)
						)
					)
					(number "8"
						(effects
							(font
								(size 1.27 1.27)
							)
						)
					)
				)
				(pin bidirectional line
					(at 20.32 -5.08 180)
					(length 2.54)
					(name "B_{2}"
						(effects
							(font
								(size 1.27 1.27)
							)
						)
					)
					(number "1"
						(effects
							(font
								(size 1.27 1.27)
							)
						)
					)
				)
				(pin power_in line
					(at 20.32 -7.62 180)
					(length 2.54)
					(name "GND"
						(effects
							(font
								(size 1.27 1.27)
							)
						)
					)
					(number "2"
						(effects
							(font
								(size 1.27 1.27)
							)
						)
					)
				)
			)
		)
	(symbol "antmicroMechanicalParts:Spacer_Drill3.7mm_H6mm_9774060151R"
			(exclude_from_sim no)
			(in_bom yes)
			(on_board yes)
			(property "Reference" "H"
				(at 22.86 -2.54 0)
				(effects
					(font
						(size 1.27 1.27)
						(thickness 0.15)
					)
					(justify left bottom)
				)
			)
			(property "Value" "Spacer_Drill3.7mm_H6mm_9774060151R"
				(at 22.86 -5.08 0)
				(effects
					(font
						(size 1.27 1.27)
						(thickness 0.15)
					)
					(justify left bottom)
					(hide yes)
				)
			)
			(property "Footprint" "antmicro-footprints:Spacer_Drill3.7mm_H6mm_9774060151R"
				(at 22.86 -7.62 0)
				(effects
					(font
						(size 1.27 1.27)
						(thickness 0.15)
					)
					(justify left bottom)
					(hide yes)
				)
			)
			(property "Datasheet" "https://www.we-online.com/components/products/datasheet/9774060151R.pdf"
				(at 22.86 -10.16 0)
				(effects
					(font
						(size 1.27 1.27)
						(thickness 0.15)
					)
					(justify left bottom)
					(hide yes)
				)
			)
			(property "Description" "Spacer, SMT, Non Stop, Steel, Swage Round, 5.1 mm x 6 mm, M2.5 Thread, WA-SMSI Series"
				(at 0 0 0)
				(effects
					(font
						(size 1.27 1.27)
					)
					(hide yes)
				)
			)
			(property "Manufacturer" "Würth Elektronik"
				(at 22.86 -12.7 0)
				(effects
					(font
						(size 1.27 1.27)
						(thickness 0.15)
					)
					(justify left bottom)
					(hide yes)
				)
			)
			(property "MPN" "9774060151R"
				(at 22.86 -15.24 0)
				(effects
					(font
						(size 1.27 1.27)
						(thickness 0.15)
					)
					(justify left bottom)
				)
			)
			(property "Author" "Antmicro"
				(at 22.86 -17.78 0)
				(effects
					(font
						(size 1.27 1.27)
						(thickness 0.15)
					)
					(justify left bottom)
					(hide yes)
				)
			)
			(property "License" "Apache-2.0"
				(at 22.86 -20.32 0)
				(effects
					(font
						(size 1.27 1.27)
						(thickness 0.15)
					)
					(justify left bottom)
					(hide yes)
				)
			)
			(property "ki_keywords" "MECHANICAL, SPACER"
				(at 0 0 0)
				(effects
					(font
						(size 1.27 1.27)
					)
					(hide yes)
				)
			)
			(symbol "Spacer_Drill3.7mm_H6mm_9774060151R_1_1"
				(rectangle
					(start 2.54 -2.54)
					(end 7.62 2.54)
					(stroke
						(width 0.254)
						(type default)
					)
					(fill
						(type background)
					)
				)
				(rectangle
					(start 3.81 -1.27)
					(end 6.35 1.27)
					(stroke
						(width 0.254)
						(type default)
					)
					(fill
						(type background)
					)
				)
				(pin passive line
					(at 0 0 0)
					(length 2.54)
					(name "~"
						(effects
							(font
								(size 1.27 1.27)
							)
						)
					)
					(number "1"
						(effects
							(font
								(size 1.27 1.27)
							)
						)
					)
				)
			)
		)
	(symbol "antmicroPMICORControllersIdealDiodes:DZDH0401DW"
			(exclude_from_sim no)
			(in_bom yes)
			(on_board yes)
			(property "Reference" "Q"
				(at 30.48 -5.08 0)
				(effects
					(font
						(size 1.27 1.27)
						(thickness 0.15)
					)
					(justify left bottom)
				)
			)
			(property "Value" "DZDH0401DW"
				(at 30.48 -7.62 0)
				(effects
					(font
						(size 1.27 1.27)
						(thickness 0.15)
					)
					(justify left bottom)
					(hide yes)
				)
			)
			(property "Footprint" "antmicro-footprints:SOT-363"
				(at 30.48 -10.16 0)
				(effects
					(font
						(size 1.27 1.27)
						(thickness 0.15)
					)
					(justify left bottom)
					(hide yes)
				)
			)
			(property "Datasheet" "https://www.mouser.com/datasheet/2/115/DIOD_S_A0011803041_1-2543705.pdf"
				(at 30.48 -12.7 0)
				(effects
					(font
						(size 1.27 1.27)
						(thickness 0.15)
					)
					(justify left bottom)
					(hide yes)
				)
			)
			(property "Description" "OR Controller N+1 ORing Controller P-Channel 1:1 SOT-363"
				(at 0 0 0)
				(effects
					(font
						(size 1.27 1.27)
					)
					(hide yes)
				)
			)
			(property "MPN" "DZDH0401DW"
				(at 30.48 -15.24 0)
				(effects
					(font
						(size 1.27 1.27)
						(thickness 0.15)
					)
					(justify left bottom)
				)
			)
			(property "Manufacturer" "Diodes Incorporated"
				(at 30.48 -17.78 0)
				(effects
					(font
						(size 1.27 1.27)
						(thickness 0.15)
					)
					(justify left bottom)
					(hide yes)
				)
			)
			(property "Author" "Antmicro"
				(at 30.48 -20.32 0)
				(effects
					(font
						(size 1.27 1.27)
						(thickness 0.15)
					)
					(justify left bottom)
					(hide yes)
				)
			)
			(property "License" "Apache-2.0"
				(at 30.48 -22.86 0)
				(effects
					(font
						(size 1.27 1.27)
						(thickness 0.15)
					)
					(justify left bottom)
					(hide yes)
				)
			)
			(property "ki_keywords" "SMT, CONTROLLER, SEMICONDUCTOR, DIODE, PMOS"
				(at 0 0 0)
				(effects
					(font
						(size 1.27 1.27)
					)
					(hide yes)
				)
			)
			(symbol "DZDH0401DW_1_0"
				(pin no_connect line
					(at 2.54 -3.81 0)
					(length 2.54)
					(hide yes)
					(name "NC"
						(effects
							(font
								(size 1.27 1.27)
							)
						)
					)
					(number "1"
						(effects
							(font
								(size 1.27 1.27)
							)
						)
					)
				)
				(pin no_connect line
					(at 13.97 -3.81 180)
					(length 2.54)
					(hide yes)
					(name "NC"
						(effects
							(font
								(size 1.27 1.27)
							)
						)
					)
					(number "5"
						(effects
							(font
								(size 1.27 1.27)
							)
						)
					)
				)
			)
			(symbol "DZDH0401DW_1_1"
				(rectangle
					(start 2.54 2.54)
					(end 13.97 -5.08)
					(stroke
						(width 0.254)
						(type default)
					)
					(fill
						(type background)
					)
				)
				(pin power_in line
					(at 0 0 0)
					(length 2.54)
					(name "D"
						(effects
							(font
								(size 1.27 1.27)
							)
						)
					)
					(number "6"
						(effects
							(font
								(size 1.27 1.27)
							)
						)
					)
				)
				(pin input line
					(at 0 -2.54 0)
					(length 2.54)
					(name "REF"
						(effects
							(font
								(size 1.27 1.27)
							)
						)
					)
					(number "2"
						(effects
							(font
								(size 1.27 1.27)
							)
						)
					)
				)
				(pin power_in line
					(at 16.51 0 180)
					(length 2.54)
					(name "S"
						(effects
							(font
								(size 1.27 1.27)
							)
						)
					)
					(number "4"
						(effects
							(font
								(size 1.27 1.27)
							)
						)
					)
				)
				(pin output line
					(at 16.51 -2.54 180)
					(length 2.54)
					(name "BIAS"
						(effects
							(font
								(size 1.27 1.27)
							)
						)
					)
					(number "3"
						(effects
							(font
								(size 1.27 1.27)
							)
						)
					)
				)
			)
		)
	(symbol "antmicroPMICPowerDistributionSwitchesLoadDrivers:AP22615A_TSOT26"
			(exclude_from_sim no)
			(in_bom yes)
			(on_board yes)
			(property "Reference" "U"
				(at 30.48 -2.54 0)
				(effects
					(font
						(size 1.27 1.27)
						(thickness 0.15)
					)
					(justify left bottom)
				)
			)
			(property "Value" "AP22615A_TSOT26"
				(at 30.48 -5.08 0)
				(effects
					(font
						(size 1.27 1.27)
						(thickness 0.15)
					)
					(justify left bottom)
					(hide yes)
				)
			)
			(property "Footprint" "antmicro-footprints:TSOT23-6"
				(at 30.48 -7.62 0)
				(effects
					(font
						(size 1.27 1.27)
						(thickness 0.15)
					)
					(justify left bottom)
					(hide yes)
				)
			)
			(property "Datasheet" "https://www.mouser.com/datasheet/2/115/DIOD_S_A0008958405_1-2543193.pdf"
				(at 30.48 -10.16 0)
				(effects
					(font
						(size 1.27 1.27)
						(thickness 0.15)
					)
					(justify left bottom)
					(hide yes)
				)
			)
			(property "Description" "Power Load Distribution Switch, High Side, Active High, 1 Output, 5.5 V, 3.6 A, 0.04 ohm, TSOT-26-6"
				(at 0 0 0)
				(effects
					(font
						(size 1.27 1.27)
					)
					(hide yes)
				)
			)
			(property "MPN" "AP22615AWU-7"
				(at 30.48 -12.7 0)
				(effects
					(font
						(size 1.27 1.27)
						(thickness 0.15)
					)
					(justify left bottom)
				)
			)
			(property "Manufacturer" "Diodes Incorporated"
				(at 30.48 -15.24 0)
				(effects
					(font
						(size 1.27 1.27)
						(thickness 0.15)
					)
					(justify left bottom)
					(hide yes)
				)
			)
			(property "Author" "Antmicro"
				(at 30.48 -17.78 0)
				(effects
					(font
						(size 1.27 1.27)
						(thickness 0.15)
					)
					(justify left bottom)
					(hide yes)
				)
			)
			(property "License" "Apache-2.0"
				(at 30.48 -20.32 0)
				(effects
					(font
						(size 1.27 1.27)
						(thickness 0.15)
					)
					(justify left bottom)
					(hide yes)
				)
			)
			(property "ki_keywords" "SMT, PMIC, IC, VOLTAGE"
				(at 0 0 0)
				(effects
					(font
						(size 1.27 1.27)
					)
					(hide yes)
				)
			)
			(symbol "AP22615A_TSOT26_1_1"
				(rectangle
					(start 2.54 2.54)
					(end 12.7 -7.62)
					(stroke
						(width 0.254)
						(type default)
					)
					(fill
						(type background)
					)
				)
				(pin power_in line
					(at 0 0 0)
					(length 2.54)
					(name "IN"
						(effects
							(font
								(size 1.27 1.27)
							)
						)
					)
					(number "6"
						(effects
							(font
								(size 1.27 1.27)
							)
						)
					)
				)
				(pin output line
					(at 0 -2.54 0)
					(length 2.54)
					(name "FLG"
						(effects
							(font
								(size 1.27 1.27)
							)
						)
					)
					(number "3"
						(effects
							(font
								(size 1.27 1.27)
							)
						)
					)
				)
				(pin input line
					(at 0 -5.08 0)
					(length 2.54)
					(name "EN"
						(effects
							(font
								(size 1.27 1.27)
							)
						)
					)
					(number "4"
						(effects
							(font
								(size 1.27 1.27)
							)
						)
					)
				)
				(pin power_out line
					(at 15.24 0 180)
					(length 2.54)
					(name "OUT"
						(effects
							(font
								(size 1.27 1.27)
							)
						)
					)
					(number "1"
						(effects
							(font
								(size 1.27 1.27)
							)
						)
					)
				)
				(pin passive line
					(at 15.24 -2.54 180)
					(length 2.54)
					(name "ISET"
						(effects
							(font
								(size 1.27 1.27)
							)
						)
					)
					(number "5"
						(effects
							(font
								(size 1.27 1.27)
							)
						)
					)
				)
				(pin power_in line
					(at 15.24 -5.08 180)
					(length 2.54)
					(name "GND"
						(effects
							(font
								(size 1.27 1.27)
							)
						)
					)
					(number "2"
						(effects
							(font
								(size 1.27 1.27)
							)
						)
					)
				)
			)
		)
	(symbol "antmicroResistors0402:R_0R_0402"
			(pin_numbers
				(hide yes)
			)
			(pin_names
				(hide yes)
			)
			(exclude_from_sim no)
			(in_bom yes)
			(on_board yes)
			(property "Reference" "R"
				(at 20.32 -5.08 0)
				(effects
					(font
						(size 1.27 1.27)
						(thickness 0.15)
					)
					(justify left bottom)
				)
			)
			(property "Value" "R_0R_0402"
				(at 20.32 -12.7 0)
				(effects
					(font
						(size 1.27 1.27)
						(thickness 0.15)
					)
					(justify left bottom)
					(hide yes)
				)
			)
			(property "Footprint" "antmicro-footprints:R_0402_1005Metric"
				(at 20.32 -15.24 0)
				(effects
					(font
						(size 1.27 1.27)
						(thickness 0.15)
					)
					(justify left bottom)
					(hide yes)
				)
			)
			(property "Datasheet" "https://industrial.panasonic.com/cdbs/www-data/pdf/RDA0000/AOA0000C301.pdf"
				(at 20.32 -17.78 0)
				(effects
					(font
						(size 1.27 1.27)
						(thickness 0.15)
					)
					(justify left bottom)
					(hide yes)
				)
			)
			(property "Description" "SMD Chip Resistor, Jumper, 0 ohm, 100 mW, 0402 [1005 Metric], Thick Film, General Purpose"
				(at 0 0 0)
				(effects
					(font
						(size 1.27 1.27)
					)
					(hide yes)
				)
			)
			(property "MPN" "ERJ2GE0R00X"
				(at 20.32 -20.32 0)
				(effects
					(font
						(size 1.27 1.27)
						(thickness 0.15)
					)
					(justify left bottom)
					(hide yes)
				)
			)
			(property "Manufacturer" "Panasonic"
				(at 20.32 -22.86 0)
				(effects
					(font
						(size 1.27 1.27)
						(thickness 0.15)
					)
					(justify left bottom)
					(hide yes)
				)
			)
			(property "License" "Apache-2.0"
				(at 20.32 -25.4 0)
				(effects
					(font
						(size 1.27 1.27)
						(thickness 0.15)
					)
					(justify left bottom)
					(hide yes)
				)
			)
			(property "Author" "Antmicro"
				(at 20.32 -27.94 0)
				(effects
					(font
						(size 1.27 1.27)
						(thickness 0.15)
					)
					(justify left bottom)
					(hide yes)
				)
			)
			(property "Val" "0R"
				(at 20.32 -7.62 0)
				(effects
					(font
						(size 1.27 1.27)
						(thickness 0.15)
					)
					(justify left bottom)
				)
			)
			(property "Tolerance" "~"
				(at 20.32 -10.16 0)
				(effects
					(font
						(size 1.27 1.27)
					)
					(justify left bottom)
					(hide yes)
				)
			)
			(property "Current" "1A"
				(at 20.32 -30.48 0)
				(effects
					(font
						(size 1.27 1.27)
						(thickness 0.15)
					)
					(justify left bottom)
					(hide yes)
				)
			)
			(property "ki_keywords" "0402, SMT, RESISTOR, PASSIVE"
				(at 0 0 0)
				(effects
					(font
						(size 1.27 1.27)
					)
					(hide yes)
				)
			)
			(symbol "R_0R_0402_0_1"
				(rectangle
					(start 0.635 0.889)
					(end 4.445 -0.889)
					(stroke
						(width 0.254)
						(type default)
					)
					(fill
						(type none)
					)
				)
			)
			(symbol "R_0R_0402_1_1"
				(pin passive line
					(at 0 0 0)
					(length 0.635)
					(name "~"
						(effects
							(font
								(size 1.27 1.27)
							)
						)
					)
					(number "1"
						(effects
							(font
								(size 1.27 1.27)
							)
						)
					)
				)
				(pin passive line
					(at 5.08 0 180)
					(length 0.635)
					(name "~"
						(effects
							(font
								(size 1.27 1.27)
							)
						)
					)
					(number "2"
						(effects
							(font
								(size 1.27 1.27)
							)
						)
					)
				)
			)
		)
	(symbol "antmicroResistors0402:R_100R_0402"
			(pin_numbers
				(hide yes)
			)
			(pin_names
				(hide yes)
			)
			(exclude_from_sim no)
			(in_bom yes)
			(on_board yes)
			(property "Reference" "R"
				(at 20.32 -5.08 0)
				(effects
					(font
						(size 1.27 1.27)
						(thickness 0.15)
					)
					(justify left bottom)
				)
			)
			(property "Value" "R_100R_0402"
				(at 20.32 -12.7 0)
				(effects
					(font
						(size 1.27 1.27)
						(thickness 0.15)
					)
					(justify left bottom)
					(hide yes)
				)
			)
			(property "Footprint" "antmicro-footprints:R_0402_1005Metric"
				(at 20.32 -15.24 0)
				(effects
					(font
						(size 1.27 1.27)
						(thickness 0.15)
					)
					(justify left bottom)
					(hide yes)
				)
			)
			(property "Datasheet" "https://www.bourns.com/docs/product-datasheets/cr.pdf"
				(at 20.32 -17.78 0)
				(effects
					(font
						(size 1.27 1.27)
						(thickness 0.15)
					)
					(justify left bottom)
					(hide yes)
				)
			)
			(property "Description" "SMD Chip Resistor, 100 ohm, ± 1%, 62.5 mW, 0402 [1005 Metric], Thick Film, General Purpose"
				(at 0 0 0)
				(effects
					(font
						(size 1.27 1.27)
					)
					(hide yes)
				)
			)
			(property "MPN" "CR0402-FX-1000GLF"
				(at 20.32 -20.32 0)
				(effects
					(font
						(size 1.27 1.27)
						(thickness 0.15)
					)
					(justify left bottom)
					(hide yes)
				)
			)
			(property "Manufacturer" "Bourns"
				(at 20.32 -22.86 0)
				(effects
					(font
						(size 1.27 1.27)
						(thickness 0.15)
					)
					(justify left bottom)
					(hide yes)
				)
			)
			(property "License" "Apache-2.0"
				(at 20.32 -25.4 0)
				(effects
					(font
						(size 1.27 1.27)
						(thickness 0.15)
					)
					(justify left bottom)
					(hide yes)
				)
			)
			(property "Author" "Antmicro"
				(at 20.32 -27.94 0)
				(effects
					(font
						(size 1.27 1.27)
						(thickness 0.15)
					)
					(justify left bottom)
					(hide yes)
				)
			)
			(property "Val" "100R"
				(at 20.32 -7.62 0)
				(effects
					(font
						(size 1.27 1.27)
						(thickness 0.15)
					)
					(justify left bottom)
				)
			)
			(property "Tolerance" "1%"
				(at 20.32 -10.16 0)
				(effects
					(font
						(size 1.27 1.27)
					)
					(justify left bottom)
					(hide yes)
				)
			)
			(property "ki_keywords" "0402, SMT, RESISTOR, PASSIVE"
				(at 0 0 0)
				(effects
					(font
						(size 1.27 1.27)
					)
					(hide yes)
				)
			)
			(symbol "R_100R_0402_0_1"
				(rectangle
					(start 0.635 0.889)
					(end 4.445 -0.889)
					(stroke
						(width 0.254)
						(type default)
					)
					(fill
						(type none)
					)
				)
			)
			(symbol "R_100R_0402_1_1"
				(pin passive line
					(at 0 0 0)
					(length 0.635)
					(name "~"
						(effects
							(font
								(size 1.27 1.27)
							)
						)
					)
					(number "1"
						(effects
							(font
								(size 1.27 1.27)
							)
						)
					)
				)
				(pin passive line
					(at 5.08 0 180)
					(length 0.635)
					(name "~"
						(effects
							(font
								(size 1.27 1.27)
							)
						)
					)
					(number "2"
						(effects
							(font
								(size 1.27 1.27)
							)
						)
					)
				)
			)
		)
	(symbol "antmicroResistors0402:R_100k_0402"
			(pin_numbers
				(hide yes)
			)
			(pin_names
				(hide yes)
			)
			(exclude_from_sim no)
			(in_bom yes)
			(on_board yes)
			(property "Reference" "R"
				(at 20.32 -5.08 0)
				(effects
					(font
						(size 1.27 1.27)
						(thickness 0.15)
					)
					(justify left bottom)
				)
			)
			(property "Value" "R_100k_0402"
				(at 20.32 -12.7 0)
				(effects
					(font
						(size 1.27 1.27)
						(thickness 0.15)
					)
					(justify left bottom)
					(hide yes)
				)
			)
			(property "Footprint" "antmicro-footprints:R_0402_1005Metric"
				(at 20.32 -15.24 0)
				(effects
					(font
						(size 1.27 1.27)
						(thickness 0.15)
					)
					(justify left bottom)
					(hide yes)
				)
			)
			(property "Datasheet" "https://www.bourns.com/docs/product-datasheets/cr.pdf"
				(at 20.32 -17.78 0)
				(effects
					(font
						(size 1.27 1.27)
						(thickness 0.15)
					)
					(justify left bottom)
					(hide yes)
				)
			)
			(property "Description" "SMD Chip Resistor, 100 kohm, ± 1%, 62.5 mW, 0402 [1005 Metric], Thick Film, General Purpose"
				(at 0 0 0)
				(effects
					(font
						(size 1.27 1.27)
					)
					(hide yes)
				)
			)
			(property "MPN" "CR0402-FX-1003GLF"
				(at 20.32 -20.32 0)
				(effects
					(font
						(size 1.27 1.27)
						(thickness 0.15)
					)
					(justify left bottom)
					(hide yes)
				)
			)
			(property "Manufacturer" "Bourns"
				(at 20.32 -22.86 0)
				(effects
					(font
						(size 1.27 1.27)
						(thickness 0.15)
					)
					(justify left bottom)
					(hide yes)
				)
			)
			(property "License" "Apache-2.0"
				(at 20.32 -25.4 0)
				(effects
					(font
						(size 1.27 1.27)
						(thickness 0.15)
					)
					(justify left bottom)
					(hide yes)
				)
			)
			(property "Author" "Antmicro"
				(at 20.32 -27.94 0)
				(effects
					(font
						(size 1.27 1.27)
						(thickness 0.15)
					)
					(justify left bottom)
					(hide yes)
				)
			)
			(property "Val" "100k"
				(at 20.32 -7.62 0)
				(effects
					(font
						(size 1.27 1.27)
						(thickness 0.15)
					)
					(justify left bottom)
				)
			)
			(property "Tolerance" "1%"
				(at 20.32 -10.16 0)
				(effects
					(font
						(size 1.27 1.27)
					)
					(justify left bottom)
					(hide yes)
				)
			)
			(property "ki_keywords" "0402, SMT, RESISTOR, PASSIVE"
				(at 0 0 0)
				(effects
					(font
						(size 1.27 1.27)
					)
					(hide yes)
				)
			)
			(symbol "R_100k_0402_0_1"
				(rectangle
					(start 0.635 0.889)
					(end 4.445 -0.889)
					(stroke
						(width 0.254)
						(type default)
					)
					(fill
						(type none)
					)
				)
			)
			(symbol "R_100k_0402_1_1"
				(pin passive line
					(at 0 0 0)
					(length 0.635)
					(name "~"
						(effects
							(font
								(size 1.27 1.27)
							)
						)
					)
					(number "1"
						(effects
							(font
								(size 1.27 1.27)
							)
						)
					)
				)
				(pin passive line
					(at 5.08 0 180)
					(length 0.635)
					(name "~"
						(effects
							(font
								(size 1.27 1.27)
							)
						)
					)
					(number "2"
						(effects
							(font
								(size 1.27 1.27)
							)
						)
					)
				)
			)
		)
	(symbol "antmicroResistors0402:R_10k_0402"
			(pin_numbers
				(hide yes)
			)
			(pin_names
				(hide yes)
			)
			(exclude_from_sim no)
			(in_bom yes)
			(on_board yes)
			(property "Reference" "R"
				(at 20.32 -5.08 0)
				(effects
					(font
						(size 1.27 1.27)
						(thickness 0.15)
					)
					(justify left bottom)
				)
			)
			(property "Value" "R_10k_0402"
				(at 20.32 -12.7 0)
				(effects
					(font
						(size 1.27 1.27)
						(thickness 0.15)
					)
					(justify left bottom)
					(hide yes)
				)
			)
			(property "Footprint" "antmicro-footprints:R_0402_1005Metric"
				(at 20.32 -15.24 0)
				(effects
					(font
						(size 1.27 1.27)
						(thickness 0.15)
					)
					(justify left bottom)
					(hide yes)
				)
			)
			(property "Datasheet" "https://www.bourns.com/docs/product-datasheets/cr.pdf"
				(at 20.32 -17.78 0)
				(effects
					(font
						(size 1.27 1.27)
						(thickness 0.15)
					)
					(justify left bottom)
					(hide yes)
				)
			)
			(property "Description" "SMD Chip Resistor, 10 kohm, ± 1%, 62.5 mW, 0402 [1005 Metric], Thick Film, General Purpose"
				(at 0 0 0)
				(effects
					(font
						(size 1.27 1.27)
					)
					(hide yes)
				)
			)
			(property "MPN" "CR0402-FX-1002GLF"
				(at 20.32 -20.32 0)
				(effects
					(font
						(size 1.27 1.27)
						(thickness 0.15)
					)
					(justify left bottom)
					(hide yes)
				)
			)
			(property "Manufacturer" "Bourns"
				(at 20.32 -22.86 0)
				(effects
					(font
						(size 1.27 1.27)
						(thickness 0.15)
					)
					(justify left bottom)
					(hide yes)
				)
			)
			(property "License" "Apache-2.0"
				(at 20.32 -25.4 0)
				(effects
					(font
						(size 1.27 1.27)
						(thickness 0.15)
					)
					(justify left bottom)
					(hide yes)
				)
			)
			(property "Author" "Antmicro"
				(at 20.32 -27.94 0)
				(effects
					(font
						(size 1.27 1.27)
						(thickness 0.15)
					)
					(justify left bottom)
					(hide yes)
				)
			)
			(property "Val" "10k"
				(at 20.32 -7.62 0)
				(effects
					(font
						(size 1.27 1.27)
						(thickness 0.15)
					)
					(justify left bottom)
				)
			)
			(property "Tolerance" "1%"
				(at 20.32 -10.16 0)
				(effects
					(font
						(size 1.27 1.27)
					)
					(justify left bottom)
					(hide yes)
				)
			)
			(property "ki_keywords" "0402, SMT, RESISTOR, PASSIVE"
				(at 0 0 0)
				(effects
					(font
						(size 1.27 1.27)
					)
					(hide yes)
				)
			)
			(symbol "R_10k_0402_0_1"
				(rectangle
					(start 0.635 0.889)
					(end 4.445 -0.889)
					(stroke
						(width 0.254)
						(type default)
					)
					(fill
						(type none)
					)
				)
			)
			(symbol "R_10k_0402_1_1"
				(pin passive line
					(at 0 0 0)
					(length 0.635)
					(name "~"
						(effects
							(font
								(size 1.27 1.27)
							)
						)
					)
					(number "1"
						(effects
							(font
								(size 1.27 1.27)
							)
						)
					)
				)
				(pin passive line
					(at 5.08 0 180)
					(length 0.635)
					(name "~"
						(effects
							(font
								(size 1.27 1.27)
							)
						)
					)
					(number "2"
						(effects
							(font
								(size 1.27 1.27)
							)
						)
					)
				)
			)
		)
	(symbol "antmicroResistors0402:R_120k_0402"
			(pin_numbers
				(hide yes)
			)
			(pin_names
				(hide yes)
			)
			(exclude_from_sim no)
			(in_bom yes)
			(on_board yes)
			(property "Reference" "R"
				(at 20.32 -5.08 0)
				(effects
					(font
						(size 1.27 1.27)
						(thickness 0.15)
					)
					(justify left bottom)
				)
			)
			(property "Value" "R_120k_0402"
				(at 20.32 -12.7 0)
				(effects
					(font
						(size 1.27 1.27)
						(thickness 0.15)
					)
					(justify left bottom)
					(hide yes)
				)
			)
			(property "Footprint" "antmicro-footprints:R_0402_1005Metric"
				(at 20.32 -15.24 0)
				(effects
					(font
						(size 1.27 1.27)
						(thickness 0.15)
					)
					(justify left bottom)
					(hide yes)
				)
			)
			(property "Datasheet" "https://www.bourns.com/docs/product-datasheets/cr.pdf"
				(at 20.32 -17.78 0)
				(effects
					(font
						(size 1.27 1.27)
						(thickness 0.15)
					)
					(justify left bottom)
					(hide yes)
				)
			)
			(property "Description" "SMD Chip Resistor, 120 kohm, ± 1%, 100 mW, 0402 [1005 Metric], Thick Film, Precision"
				(at 0 0 0)
				(effects
					(font
						(size 1.27 1.27)
					)
					(hide yes)
				)
			)
			(property "MPN" "CR0402-FX-1203GLF"
				(at 20.32 -20.32 0)
				(effects
					(font
						(size 1.27 1.27)
						(thickness 0.15)
					)
					(justify left bottom)
					(hide yes)
				)
			)
			(property "Manufacturer" "Bourns"
				(at 20.32 -22.86 0)
				(effects
					(font
						(size 1.27 1.27)
						(thickness 0.15)
					)
					(justify left bottom)
					(hide yes)
				)
			)
			(property "License" "Apache-2.0"
				(at 20.32 -25.4 0)
				(effects
					(font
						(size 1.27 1.27)
						(thickness 0.15)
					)
					(justify left bottom)
					(hide yes)
				)
			)
			(property "Author" "Antmicro"
				(at 20.32 -27.94 0)
				(effects
					(font
						(size 1.27 1.27)
						(thickness 0.15)
					)
					(justify left bottom)
					(hide yes)
				)
			)
			(property "Val" "120k"
				(at 20.32 -7.62 0)
				(effects
					(font
						(size 1.27 1.27)
						(thickness 0.15)
					)
					(justify left bottom)
				)
			)
			(property "Tolerance" "1%"
				(at 20.32 -10.16 0)
				(effects
					(font
						(size 1.27 1.27)
					)
					(justify left bottom)
					(hide yes)
				)
			)
			(property "ki_keywords" "0402, SMT, RESISTOR, PASSIVE"
				(at 0 0 0)
				(effects
					(font
						(size 1.27 1.27)
					)
					(hide yes)
				)
			)
			(symbol "R_120k_0402_0_1"
				(rectangle
					(start 0.635 0.889)
					(end 4.445 -0.889)
					(stroke
						(width 0.254)
						(type default)
					)
					(fill
						(type none)
					)
				)
			)
			(symbol "R_120k_0402_1_1"
				(pin passive line
					(at 0 0 0)
					(length 0.635)
					(name "~"
						(effects
							(font
								(size 1.27 1.27)
							)
						)
					)
					(number "1"
						(effects
							(font
								(size 1.27 1.27)
							)
						)
					)
				)
				(pin passive line
					(at 5.08 0 180)
					(length 0.635)
					(name "~"
						(effects
							(font
								(size 1.27 1.27)
							)
						)
					)
					(number "2"
						(effects
							(font
								(size 1.27 1.27)
							)
						)
					)
				)
			)
		)
	(symbol "antmicroResistors0402:R_12k4_0402"
			(pin_numbers
				(hide yes)
			)
			(pin_names
				(hide yes)
			)
			(exclude_from_sim no)
			(in_bom yes)
			(on_board yes)
			(property "Reference" "R"
				(at 20.32 -5.08 0)
				(effects
					(font
						(size 1.27 1.27)
						(thickness 0.15)
					)
					(justify left bottom)
				)
			)
			(property "Value" "R_12k4_0402"
				(at 20.32 -12.7 0)
				(effects
					(font
						(size 1.27 1.27)
						(thickness 0.15)
					)
					(justify left bottom)
					(hide yes)
				)
			)
			(property "Footprint" "antmicro-footprints:R_0402_1005Metric"
				(at 20.32 -15.24 0)
				(effects
					(font
						(size 1.27 1.27)
						(thickness 0.15)
					)
					(justify left bottom)
					(hide yes)
				)
			)
			(property "Datasheet" "https://www.bourns.com/docs/product-datasheets/cr.pdf"
				(at 20.32 -17.78 0)
				(effects
					(font
						(size 1.27 1.27)
						(thickness 0.15)
					)
					(justify left bottom)
					(hide yes)
				)
			)
			(property "Description" "SMD Chip Resistor, 12.4 kohm, ± 1%, 62.5 mW, 0402 [1005 Metric], Thick Film, General Purpose"
				(at 0 0 0)
				(effects
					(font
						(size 1.27 1.27)
					)
					(hide yes)
				)
			)
			(property "MPN" "CR0402-FX-1242GLF"
				(at 20.32 -20.32 0)
				(effects
					(font
						(size 1.27 1.27)
						(thickness 0.15)
					)
					(justify left bottom)
					(hide yes)
				)
			)
			(property "Manufacturer" "Bourns"
				(at 20.32 -22.86 0)
				(effects
					(font
						(size 1.27 1.27)
						(thickness 0.15)
					)
					(justify left bottom)
					(hide yes)
				)
			)
			(property "License" "Apache-2.0"
				(at 20.32 -25.4 0)
				(effects
					(font
						(size 1.27 1.27)
						(thickness 0.15)
					)
					(justify left bottom)
					(hide yes)
				)
			)
			(property "Author" "Antmicro"
				(at 20.32 -27.94 0)
				(effects
					(font
						(size 1.27 1.27)
						(thickness 0.15)
					)
					(justify left bottom)
					(hide yes)
				)
			)
			(property "Val" "12k4"
				(at 20.32 -7.62 0)
				(effects
					(font
						(size 1.27 1.27)
						(thickness 0.15)
					)
					(justify left bottom)
				)
			)
			(property "Tolerance" "1%"
				(at 20.32 -10.16 0)
				(effects
					(font
						(size 1.27 1.27)
					)
					(justify left bottom)
					(hide yes)
				)
			)
			(property "ki_keywords" "0402, SMT, RESISTOR, PASSIVE"
				(at 0 0 0)
				(effects
					(font
						(size 1.27 1.27)
					)
					(hide yes)
				)
			)
			(symbol "R_12k4_0402_0_1"
				(rectangle
					(start 0.635 0.889)
					(end 4.445 -0.889)
					(stroke
						(width 0.254)
						(type default)
					)
					(fill
						(type none)
					)
				)
			)
			(symbol "R_12k4_0402_1_1"
				(pin passive line
					(at 0 0 0)
					(length 0.635)
					(name "~"
						(effects
							(font
								(size 1.27 1.27)
							)
						)
					)
					(number "1"
						(effects
							(font
								(size 1.27 1.27)
							)
						)
					)
				)
				(pin passive line
					(at 5.08 0 180)
					(length 0.635)
					(name "~"
						(effects
							(font
								(size 1.27 1.27)
							)
						)
					)
					(number "2"
						(effects
							(font
								(size 1.27 1.27)
							)
						)
					)
				)
			)
		)
	(symbol "antmicroResistors0402:R_13k7_0402"
			(pin_numbers
				(hide yes)
			)
			(pin_names
				(hide yes)
			)
			(exclude_from_sim no)
			(in_bom yes)
			(on_board yes)
			(property "Reference" "R"
				(at 20.32 -5.08 0)
				(effects
					(font
						(size 1.27 1.27)
						(thickness 0.15)
					)
					(justify left bottom)
				)
			)
			(property "Value" "R_13k7_0402"
				(at 20.32 -12.7 0)
				(effects
					(font
						(size 1.27 1.27)
						(thickness 0.15)
					)
					(justify left bottom)
					(hide yes)
				)
			)
			(property "Footprint" "antmicro-footprints:R_0402_1005Metric"
				(at 20.32 -15.24 0)
				(effects
					(font
						(size 1.27 1.27)
						(thickness 0.15)
					)
					(justify left bottom)
					(hide yes)
				)
			)
			(property "Datasheet" "https://www.bourns.com/docs/product-datasheets/cr.pdf"
				(at 20.32 -17.78 0)
				(effects
					(font
						(size 1.27 1.27)
						(thickness 0.15)
					)
					(justify left bottom)
					(hide yes)
				)
			)
			(property "Description" "SMD Chip Resistor, Ceramic, 13.7 kohm, ± 1%, 62.5 mW, 0402 [1005 Metric], Thick Film"
				(at 0 0 0)
				(effects
					(font
						(size 1.27 1.27)
					)
					(hide yes)
				)
			)
			(property "MPN" "CR0402-FX-1372GLF"
				(at 20.32 -20.32 0)
				(effects
					(font
						(size 1.27 1.27)
						(thickness 0.15)
					)
					(justify left bottom)
					(hide yes)
				)
			)
			(property "Manufacturer" "Bourns"
				(at 20.32 -22.86 0)
				(effects
					(font
						(size 1.27 1.27)
						(thickness 0.15)
					)
					(justify left bottom)
					(hide yes)
				)
			)
			(property "License" "Apache-2.0"
				(at 20.32 -25.4 0)
				(effects
					(font
						(size 1.27 1.27)
						(thickness 0.15)
					)
					(justify left bottom)
					(hide yes)
				)
			)
			(property "Author" "Antmicro"
				(at 20.32 -27.94 0)
				(effects
					(font
						(size 1.27 1.27)
						(thickness 0.15)
					)
					(justify left bottom)
					(hide yes)
				)
			)
			(property "Val" "13k7"
				(at 20.32 -7.62 0)
				(effects
					(font
						(size 1.27 1.27)
						(thickness 0.15)
					)
					(justify left bottom)
				)
			)
			(property "Tolerance" "1%"
				(at 20.32 -10.16 0)
				(effects
					(font
						(size 1.27 1.27)
					)
					(justify left bottom)
					(hide yes)
				)
			)
			(property "ki_keywords" "0402, SMT, RESISTOR, PASSIVE"
				(at 0 0 0)
				(effects
					(font
						(size 1.27 1.27)
					)
					(hide yes)
				)
			)
			(symbol "R_13k7_0402_0_1"
				(rectangle
					(start 0.635 0.889)
					(end 4.445 -0.889)
					(stroke
						(width 0.254)
						(type default)
					)
					(fill
						(type none)
					)
				)
			)
			(symbol "R_13k7_0402_1_1"
				(pin passive line
					(at 0 0 0)
					(length 0.635)
					(name "~"
						(effects
							(font
								(size 1.27 1.27)
							)
						)
					)
					(number "1"
						(effects
							(font
								(size 1.27 1.27)
							)
						)
					)
				)
				(pin passive line
					(at 5.08 0 180)
					(length 0.635)
					(name "~"
						(effects
							(font
								(size 1.27 1.27)
							)
						)
					)
					(number "2"
						(effects
							(font
								(size 1.27 1.27)
							)
						)
					)
				)
			)
		)
	(symbol "antmicroResistors0402:R_1M_0402"
			(pin_numbers
				(hide yes)
			)
			(pin_names
				(hide yes)
			)
			(exclude_from_sim no)
			(in_bom yes)
			(on_board yes)
			(property "Reference" "R"
				(at 20.32 -5.08 0)
				(effects
					(font
						(size 1.27 1.27)
						(thickness 0.15)
					)
					(justify left bottom)
				)
			)
			(property "Value" "R_1M_0402"
				(at 20.32 -12.7 0)
				(effects
					(font
						(size 1.27 1.27)
						(thickness 0.15)
					)
					(justify left bottom)
					(hide yes)
				)
			)
			(property "Footprint" "antmicro-footprints:R_0402_1005Metric"
				(at 20.32 -15.24 0)
				(effects
					(font
						(size 1.27 1.27)
						(thickness 0.15)
					)
					(justify left bottom)
					(hide yes)
				)
			)
			(property "Datasheet" "https://www.bourns.com/docs/product-datasheets/cr.pdf"
				(at 20.32 -17.78 0)
				(effects
					(font
						(size 1.27 1.27)
						(thickness 0.15)
					)
					(justify left bottom)
					(hide yes)
				)
			)
			(property "Description" "SMD Chip Resistor, 1 Mohm, ± 1%, 62.5 mW, 0402 [1005 Metric], Thick Film, General Purpose"
				(at 0 0 0)
				(effects
					(font
						(size 1.27 1.27)
					)
					(hide yes)
				)
			)
			(property "MPN" "CR0402-FX-1004GLF"
				(at 20.32 -20.32 0)
				(effects
					(font
						(size 1.27 1.27)
						(thickness 0.15)
					)
					(justify left bottom)
					(hide yes)
				)
			)
			(property "Manufacturer" "Bourns"
				(at 20.32 -22.86 0)
				(effects
					(font
						(size 1.27 1.27)
						(thickness 0.15)
					)
					(justify left bottom)
					(hide yes)
				)
			)
			(property "License" "Apache-2.0"
				(at 20.32 -25.4 0)
				(effects
					(font
						(size 1.27 1.27)
						(thickness 0.15)
					)
					(justify left bottom)
					(hide yes)
				)
			)
			(property "Author" "Antmicro"
				(at 20.32 -27.94 0)
				(effects
					(font
						(size 1.27 1.27)
						(thickness 0.15)
					)
					(justify left bottom)
					(hide yes)
				)
			)
			(property "Val" "1M"
				(at 20.32 -7.62 0)
				(effects
					(font
						(size 1.27 1.27)
						(thickness 0.15)
					)
					(justify left bottom)
				)
			)
			(property "Tolerance" "1%"
				(at 20.32 -10.16 0)
				(effects
					(font
						(size 1.27 1.27)
					)
					(justify left bottom)
					(hide yes)
				)
			)
			(property "ki_keywords" "0402, SMT, RESISTOR, PASSIVE"
				(at 0 0 0)
				(effects
					(font
						(size 1.27 1.27)
					)
					(hide yes)
				)
			)
			(symbol "R_1M_0402_0_1"
				(rectangle
					(start 0.635 0.889)
					(end 4.445 -0.889)
					(stroke
						(width 0.254)
						(type default)
					)
					(fill
						(type none)
					)
				)
			)
			(symbol "R_1M_0402_1_1"
				(pin passive line
					(at 0 0 0)
					(length 0.635)
					(name "~"
						(effects
							(font
								(size 1.27 1.27)
							)
						)
					)
					(number "1"
						(effects
							(font
								(size 1.27 1.27)
							)
						)
					)
				)
				(pin passive line
					(at 5.08 0 180)
					(length 0.635)
					(name "~"
						(effects
							(font
								(size 1.27 1.27)
							)
						)
					)
					(number "2"
						(effects
							(font
								(size 1.27 1.27)
							)
						)
					)
				)
			)
		)
	(symbol "antmicroResistors0402:R_1k65_0402"
			(pin_numbers
				(hide yes)
			)
			(pin_names
				(hide yes)
			)
			(exclude_from_sim no)
			(in_bom yes)
			(on_board yes)
			(property "Reference" "R"
				(at 20.32 -5.08 0)
				(effects
					(font
						(size 1.27 1.27)
						(thickness 0.15)
					)
					(justify left bottom)
				)
			)
			(property "Value" "R_1k65_0402"
				(at 20.32 -12.7 0)
				(effects
					(font
						(size 1.27 1.27)
						(thickness 0.15)
					)
					(justify left bottom)
					(hide yes)
				)
			)
			(property "Footprint" "antmicro-footprints:R_0402_1005Metric"
				(at 20.32 -15.24 0)
				(effects
					(font
						(size 1.27 1.27)
						(thickness 0.15)
					)
					(justify left bottom)
					(hide yes)
				)
			)
			(property "Datasheet" "https://www.farnell.com/datasheets/3795017.pdf"
				(at 20.32 -17.78 0)
				(effects
					(font
						(size 1.27 1.27)
						(thickness 0.15)
					)
					(justify left bottom)
					(hide yes)
				)
			)
			(property "Description" "SMD Chip Resistor, 1.65 kohm, ± 1%, 63 mW, 0402 [1005 Metric], Thick Film, General Purpose"
				(at 0 0 0)
				(effects
					(font
						(size 1.27 1.27)
					)
					(hide yes)
				)
			)
			(property "MPN" "RC0402FR-071K65L"
				(at 20.32 -20.32 0)
				(effects
					(font
						(size 1.27 1.27)
						(thickness 0.15)
					)
					(justify left bottom)
					(hide yes)
				)
			)
			(property "Manufacturer" "YAGEO"
				(at 20.32 -22.86 0)
				(effects
					(font
						(size 1.27 1.27)
						(thickness 0.15)
					)
					(justify left bottom)
					(hide yes)
				)
			)
			(property "License" "Apache-2.0"
				(at 20.32 -25.4 0)
				(effects
					(font
						(size 1.27 1.27)
						(thickness 0.15)
					)
					(justify left bottom)
					(hide yes)
				)
			)
			(property "Author" "Antmicro"
				(at 20.32 -27.94 0)
				(effects
					(font
						(size 1.27 1.27)
						(thickness 0.15)
					)
					(justify left bottom)
					(hide yes)
				)
			)
			(property "Val" "1k65"
				(at 20.32 -7.62 0)
				(effects
					(font
						(size 1.27 1.27)
						(thickness 0.15)
					)
					(justify left bottom)
				)
			)
			(property "Tolerance" "1%"
				(at 20.32 -10.16 0)
				(effects
					(font
						(size 1.27 1.27)
					)
					(justify left bottom)
					(hide yes)
				)
			)
			(property "ki_keywords" "0402, SMT, RESISTOR, PASSIVE"
				(at 0 0 0)
				(effects
					(font
						(size 1.27 1.27)
					)
					(hide yes)
				)
			)
			(symbol "R_1k65_0402_0_1"
				(rectangle
					(start 0.635 0.889)
					(end 4.445 -0.889)
					(stroke
						(width 0.254)
						(type default)
					)
					(fill
						(type none)
					)
				)
			)
			(symbol "R_1k65_0402_1_1"
				(pin passive line
					(at 0 0 0)
					(length 0.635)
					(name "~"
						(effects
							(font
								(size 1.27 1.27)
							)
						)
					)
					(number "1"
						(effects
							(font
								(size 1.27 1.27)
							)
						)
					)
				)
				(pin passive line
					(at 5.08 0 180)
					(length 0.635)
					(name "~"
						(effects
							(font
								(size 1.27 1.27)
							)
						)
					)
					(number "2"
						(effects
							(font
								(size 1.27 1.27)
							)
						)
					)
				)
			)
		)
	(symbol "antmicroResistors0402:R_200R_0402"
			(pin_numbers
				(hide yes)
			)
			(pin_names
				(hide yes)
			)
			(exclude_from_sim no)
			(in_bom yes)
			(on_board yes)
			(property "Reference" "R"
				(at 20.32 -5.08 0)
				(effects
					(font
						(size 1.27 1.27)
						(thickness 0.15)
					)
					(justify left bottom)
				)
			)
			(property "Value" "R_200R_0402"
				(at 20.32 -12.7 0)
				(effects
					(font
						(size 1.27 1.27)
						(thickness 0.15)
					)
					(justify left bottom)
					(hide yes)
				)
			)
			(property "Footprint" "antmicro-footprints:R_0402_1005Metric"
				(at 20.32 -15.24 0)
				(effects
					(font
						(size 1.27 1.27)
						(thickness 0.15)
					)
					(justify left bottom)
					(hide yes)
				)
			)
			(property "Datasheet" "https://www.bourns.com/docs/product-datasheets/cr.pdf"
				(at 20.32 -17.78 0)
				(effects
					(font
						(size 1.27 1.27)
						(thickness 0.15)
					)
					(justify left bottom)
					(hide yes)
				)
			)
			(property "Description" "SMD Chip Resistor, 200 ohm, ± 1%, 62.5 mW, 0402 [1005 Metric], Thick Film, General Purpose"
				(at 0 0 0)
				(effects
					(font
						(size 1.27 1.27)
					)
					(hide yes)
				)
			)
			(property "MPN" "CR0402-FX-2000GLF"
				(at 20.32 -20.32 0)
				(effects
					(font
						(size 1.27 1.27)
						(thickness 0.15)
					)
					(justify left bottom)
					(hide yes)
				)
			)
			(property "Manufacturer" "Bourns"
				(at 20.32 -22.86 0)
				(effects
					(font
						(size 1.27 1.27)
						(thickness 0.15)
					)
					(justify left bottom)
					(hide yes)
				)
			)
			(property "License" "Apache-2.0"
				(at 20.32 -25.4 0)
				(effects
					(font
						(size 1.27 1.27)
						(thickness 0.15)
					)
					(justify left bottom)
					(hide yes)
				)
			)
			(property "Author" "Antmicro"
				(at 20.32 -27.94 0)
				(effects
					(font
						(size 1.27 1.27)
						(thickness 0.15)
					)
					(justify left bottom)
					(hide yes)
				)
			)
			(property "Val" "200R"
				(at 20.32 -7.62 0)
				(effects
					(font
						(size 1.27 1.27)
						(thickness 0.15)
					)
					(justify left bottom)
				)
			)
			(property "Tolerance" "1%"
				(at 20.32 -10.16 0)
				(effects
					(font
						(size 1.27 1.27)
					)
					(justify left bottom)
					(hide yes)
				)
			)
			(property "ki_keywords" "0402, SMT, RESISTOR, PASSIVE"
				(at 0 0 0)
				(effects
					(font
						(size 1.27 1.27)
					)
					(hide yes)
				)
			)
			(symbol "R_200R_0402_0_1"
				(rectangle
					(start 0.635 0.889)
					(end 4.445 -0.889)
					(stroke
						(width 0.254)
						(type default)
					)
					(fill
						(type none)
					)
				)
			)
			(symbol "R_200R_0402_1_1"
				(pin passive line
					(at 0 0 0)
					(length 0.635)
					(name "~"
						(effects
							(font
								(size 1.27 1.27)
							)
						)
					)
					(number "1"
						(effects
							(font
								(size 1.27 1.27)
							)
						)
					)
				)
				(pin passive line
					(at 5.08 0 180)
					(length 0.635)
					(name "~"
						(effects
							(font
								(size 1.27 1.27)
							)
						)
					)
					(number "2"
						(effects
							(font
								(size 1.27 1.27)
							)
						)
					)
				)
			)
		)
	(symbol "antmicroResistors0402:R_2k2_0402"
			(pin_numbers
				(hide yes)
			)
			(pin_names
				(hide yes)
			)
			(exclude_from_sim no)
			(in_bom yes)
			(on_board yes)
			(property "Reference" "R"
				(at 20.32 -5.08 0)
				(effects
					(font
						(size 1.27 1.27)
						(thickness 0.15)
					)
					(justify left bottom)
				)
			)
			(property "Value" "R_2k2_0402"
				(at 20.32 -12.7 0)
				(effects
					(font
						(size 1.27 1.27)
						(thickness 0.15)
					)
					(justify left bottom)
					(hide yes)
				)
			)
			(property "Footprint" "antmicro-footprints:R_0402_1005Metric"
				(at 20.32 -15.24 0)
				(effects
					(font
						(size 1.27 1.27)
						(thickness 0.15)
					)
					(justify left bottom)
					(hide yes)
				)
			)
			(property "Datasheet" "https://www.bourns.com/docs/product-datasheets/cr.pdf"
				(at 20.32 -17.78 0)
				(effects
					(font
						(size 1.27 1.27)
						(thickness 0.15)
					)
					(justify left bottom)
					(hide yes)
				)
			)
			(property "Description" "SMD Chip Resistor, 2.2 kohm, ± 1%, 62.5 mW, 0402 [1005 Metric], Thick Film, General Purpose"
				(at 0 0 0)
				(effects
					(font
						(size 1.27 1.27)
					)
					(hide yes)
				)
			)
			(property "MPN" "CR0402-FX-2201GLF"
				(at 20.32 -20.32 0)
				(effects
					(font
						(size 1.27 1.27)
						(thickness 0.15)
					)
					(justify left bottom)
					(hide yes)
				)
			)
			(property "Manufacturer" "Bourns"
				(at 20.32 -22.86 0)
				(effects
					(font
						(size 1.27 1.27)
						(thickness 0.15)
					)
					(justify left bottom)
					(hide yes)
				)
			)
			(property "License" "Apache-2.0"
				(at 20.32 -25.4 0)
				(effects
					(font
						(size 1.27 1.27)
						(thickness 0.15)
					)
					(justify left bottom)
					(hide yes)
				)
			)
			(property "Author" "Antmicro"
				(at 20.32 -27.94 0)
				(effects
					(font
						(size 1.27 1.27)
						(thickness 0.15)
					)
					(justify left bottom)
					(hide yes)
				)
			)
			(property "Val" "2k2"
				(at 20.32 -7.62 0)
				(effects
					(font
						(size 1.27 1.27)
						(thickness 0.15)
					)
					(justify left bottom)
				)
			)
			(property "Tolerance" "1%"
				(at 20.32 -10.16 0)
				(effects
					(font
						(size 1.27 1.27)
					)
					(justify left bottom)
					(hide yes)
				)
			)
			(property "ki_keywords" "0402, SMT, RESISTOR, PASSIVE"
				(at 0 0 0)
				(effects
					(font
						(size 1.27 1.27)
					)
					(hide yes)
				)
			)
			(symbol "R_2k2_0402_0_1"
				(rectangle
					(start 0.635 0.889)
					(end 4.445 -0.889)
					(stroke
						(width 0.254)
						(type default)
					)
					(fill
						(type none)
					)
				)
			)
			(symbol "R_2k2_0402_1_1"
				(pin passive line
					(at 0 0 0)
					(length 0.635)
					(name "~"
						(effects
							(font
								(size 1.27 1.27)
							)
						)
					)
					(number "1"
						(effects
							(font
								(size 1.27 1.27)
							)
						)
					)
				)
				(pin passive line
					(at 5.08 0 180)
					(length 0.635)
					(name "~"
						(effects
							(font
								(size 1.27 1.27)
							)
						)
					)
					(number "2"
						(effects
							(font
								(size 1.27 1.27)
							)
						)
					)
				)
			)
		)
	(symbol "antmicroResistors0402:R_402R_0402"
			(pin_numbers
				(hide yes)
			)
			(pin_names
				(hide yes)
			)
			(exclude_from_sim no)
			(in_bom yes)
			(on_board yes)
			(property "Reference" "R"
				(at 20.32 -5.08 0)
				(effects
					(font
						(size 1.27 1.27)
						(thickness 0.15)
					)
					(justify left bottom)
				)
			)
			(property "Value" "R_402R_0402"
				(at 20.32 -12.7 0)
				(effects
					(font
						(size 1.27 1.27)
						(thickness 0.15)
					)
					(justify left bottom)
					(hide yes)
				)
			)
			(property "Footprint" "antmicro-footprints:R_0402_1005Metric"
				(at 20.32 -15.24 0)
				(effects
					(font
						(size 1.27 1.27)
						(thickness 0.15)
					)
					(justify left bottom)
					(hide yes)
				)
			)
			(property "Datasheet" "https://www.mouser.com/datasheet/2/54/cr-1858361.pdf"
				(at 20.32 -17.78 0)
				(effects
					(font
						(size 1.27 1.27)
						(thickness 0.15)
					)
					(justify left bottom)
					(hide yes)
				)
			)
			(property "Description" "SMD Chip Resistor, 402 ohm, ± 1%, 63 mW, 0402 [1005 Metric], Thick Film, General Purpose"
				(at 0 0 0)
				(effects
					(font
						(size 1.27 1.27)
					)
					(hide yes)
				)
			)
			(property "MPN" "CR0402-FX-4020GLF"
				(at 20.32 -20.32 0)
				(effects
					(font
						(size 1.27 1.27)
						(thickness 0.15)
					)
					(justify left bottom)
					(hide yes)
				)
			)
			(property "Manufacturer" "Bourns"
				(at 20.32 -22.86 0)
				(effects
					(font
						(size 1.27 1.27)
						(thickness 0.15)
					)
					(justify left bottom)
					(hide yes)
				)
			)
			(property "License" "Apache-2.0"
				(at 20.32 -25.4 0)
				(effects
					(font
						(size 1.27 1.27)
						(thickness 0.15)
					)
					(justify left bottom)
					(hide yes)
				)
			)
			(property "Author" "Antmicro"
				(at 20.32 -27.94 0)
				(effects
					(font
						(size 1.27 1.27)
						(thickness 0.15)
					)
					(justify left bottom)
					(hide yes)
				)
			)
			(property "Val" "402R"
				(at 20.32 -7.62 0)
				(effects
					(font
						(size 1.27 1.27)
						(thickness 0.15)
					)
					(justify left bottom)
				)
			)
			(property "Tolerance" "1%"
				(at 20.32 -10.16 0)
				(effects
					(font
						(size 1.27 1.27)
					)
					(justify left bottom)
					(hide yes)
				)
			)
			(property "ki_keywords" "0402, SMT, RESISTOR, PASSIVE"
				(at 0 0 0)
				(effects
					(font
						(size 1.27 1.27)
					)
					(hide yes)
				)
			)
			(symbol "R_402R_0402_0_1"
				(rectangle
					(start 0.635 0.889)
					(end 4.445 -0.889)
					(stroke
						(width 0.254)
						(type default)
					)
					(fill
						(type none)
					)
				)
			)
			(symbol "R_402R_0402_1_1"
				(pin passive line
					(at 0 0 0)
					(length 0.635)
					(name "~"
						(effects
							(font
								(size 1.27 1.27)
							)
						)
					)
					(number "1"
						(effects
							(font
								(size 1.27 1.27)
							)
						)
					)
				)
				(pin passive line
					(at 5.08 0 180)
					(length 0.635)
					(name "~"
						(effects
							(font
								(size 1.27 1.27)
							)
						)
					)
					(number "2"
						(effects
							(font
								(size 1.27 1.27)
							)
						)
					)
				)
			)
		)
	(symbol "antmicroResistors0402:R_40k2_0402"
			(pin_numbers
				(hide yes)
			)
			(pin_names
				(hide yes)
			)
			(exclude_from_sim no)
			(in_bom yes)
			(on_board yes)
			(property "Reference" "R"
				(at 20.32 -5.08 0)
				(effects
					(font
						(size 1.27 1.27)
						(thickness 0.15)
					)
					(justify left bottom)
				)
			)
			(property "Value" "R_40k2_0402"
				(at 20.32 -12.7 0)
				(effects
					(font
						(size 1.27 1.27)
						(thickness 0.15)
					)
					(justify left bottom)
					(hide yes)
				)
			)
			(property "Footprint" "antmicro-footprints:R_0402_1005Metric"
				(at 20.32 -15.24 0)
				(effects
					(font
						(size 1.27 1.27)
						(thickness 0.15)
					)
					(justify left bottom)
					(hide yes)
				)
			)
			(property "Datasheet" "https://www.bourns.com/docs/product-datasheets/cr.pdf"
				(at 20.32 -17.78 0)
				(effects
					(font
						(size 1.27 1.27)
						(thickness 0.15)
					)
					(justify left bottom)
					(hide yes)
				)
			)
			(property "Description" "SMD Chip Resistor, 40.2 kohm, ± 1%, 63 mW, 0402 [1005 Metric], Thick Film, General Purpose"
				(at 0 0 0)
				(effects
					(font
						(size 1.27 1.27)
					)
					(hide yes)
				)
			)
			(property "MPN" "CR0402-FX-4022GLF"
				(at 20.32 -20.32 0)
				(effects
					(font
						(size 1.27 1.27)
						(thickness 0.15)
					)
					(justify left bottom)
					(hide yes)
				)
			)
			(property "Manufacturer" "Bourns"
				(at 20.32 -22.86 0)
				(effects
					(font
						(size 1.27 1.27)
						(thickness 0.15)
					)
					(justify left bottom)
					(hide yes)
				)
			)
			(property "License" "Apache-2.0"
				(at 20.32 -25.4 0)
				(effects
					(font
						(size 1.27 1.27)
						(thickness 0.15)
					)
					(justify left bottom)
					(hide yes)
				)
			)
			(property "Author" "Antmicro"
				(at 20.32 -27.94 0)
				(effects
					(font
						(size 1.27 1.27)
						(thickness 0.15)
					)
					(justify left bottom)
					(hide yes)
				)
			)
			(property "Val" "40k2"
				(at 20.32 -7.62 0)
				(effects
					(font
						(size 1.27 1.27)
						(thickness 0.15)
					)
					(justify left bottom)
				)
			)
			(property "Tolerance" "1%"
				(at 20.32 -10.16 0)
				(effects
					(font
						(size 1.27 1.27)
					)
					(justify left bottom)
					(hide yes)
				)
			)
			(property "ki_keywords" "0402, SMT, RESISTOR, PASSIVE"
				(at 0 0 0)
				(effects
					(font
						(size 1.27 1.27)
					)
					(hide yes)
				)
			)
			(symbol "R_40k2_0402_0_1"
				(rectangle
					(start 0.635 0.889)
					(end 4.445 -0.889)
					(stroke
						(width 0.254)
						(type default)
					)
					(fill
						(type none)
					)
				)
			)
			(symbol "R_40k2_0402_1_1"
				(pin passive line
					(at 0 0 0)
					(length 0.635)
					(name "~"
						(effects
							(font
								(size 1.27 1.27)
							)
						)
					)
					(number "1"
						(effects
							(font
								(size 1.27 1.27)
							)
						)
					)
				)
				(pin passive line
					(at 5.08 0 180)
					(length 0.635)
					(name "~"
						(effects
							(font
								(size 1.27 1.27)
							)
						)
					)
					(number "2"
						(effects
							(font
								(size 1.27 1.27)
							)
						)
					)
				)
			)
		)
	(symbol "antmicroResistors0402:R_470R_0402"
			(pin_numbers
				(hide yes)
			)
			(pin_names
				(hide yes)
			)
			(exclude_from_sim no)
			(in_bom yes)
			(on_board yes)
			(property "Reference" "R"
				(at 20.32 -5.08 0)
				(effects
					(font
						(size 1.27 1.27)
						(thickness 0.15)
					)
					(justify left bottom)
				)
			)
			(property "Value" "R_470R_0402"
				(at 20.32 -12.7 0)
				(effects
					(font
						(size 1.27 1.27)
						(thickness 0.15)
					)
					(justify left bottom)
					(hide yes)
				)
			)
			(property "Footprint" "antmicro-footprints:R_0402_1005Metric"
				(at 20.32 -15.24 0)
				(effects
					(font
						(size 1.27 1.27)
						(thickness 0.15)
					)
					(justify left bottom)
					(hide yes)
				)
			)
			(property "Datasheet" "https://www.bourns.com/docs/product-datasheets/cr.pdf"
				(at 20.32 -17.78 0)
				(effects
					(font
						(size 1.27 1.27)
						(thickness 0.15)
					)
					(justify left bottom)
					(hide yes)
				)
			)
			(property "Description" "SMD Chip Resistor, 470 ohm, ± 1%, 62.5 mW, 0402 [1005 Metric], Thick Film, General Purpose"
				(at 0 0 0)
				(effects
					(font
						(size 1.27 1.27)
					)
					(hide yes)
				)
			)
			(property "MPN" "CR0402-FX-4700GLF"
				(at 20.32 -20.32 0)
				(effects
					(font
						(size 1.27 1.27)
						(thickness 0.15)
					)
					(justify left bottom)
					(hide yes)
				)
			)
			(property "Manufacturer" "Bourns"
				(at 20.32 -22.86 0)
				(effects
					(font
						(size 1.27 1.27)
						(thickness 0.15)
					)
					(justify left bottom)
					(hide yes)
				)
			)
			(property "License" "Apache-2.0"
				(at 20.32 -25.4 0)
				(effects
					(font
						(size 1.27 1.27)
						(thickness 0.15)
					)
					(justify left bottom)
					(hide yes)
				)
			)
			(property "Author" "Antmicro"
				(at 20.32 -27.94 0)
				(effects
					(font
						(size 1.27 1.27)
						(thickness 0.15)
					)
					(justify left bottom)
					(hide yes)
				)
			)
			(property "Val" "470R"
				(at 20.32 -7.62 0)
				(effects
					(font
						(size 1.27 1.27)
						(thickness 0.15)
					)
					(justify left bottom)
				)
			)
			(property "Tolerance" "1%"
				(at 20.32 -10.16 0)
				(effects
					(font
						(size 1.27 1.27)
					)
					(justify left bottom)
					(hide yes)
				)
			)
			(property "ki_keywords" "0402, SMT, RESISTOR, PASSIVE"
				(at 0 0 0)
				(effects
					(font
						(size 1.27 1.27)
					)
					(hide yes)
				)
			)
			(symbol "R_470R_0402_0_1"
				(rectangle
					(start 0.635 0.889)
					(end 4.445 -0.889)
					(stroke
						(width 0.254)
						(type default)
					)
					(fill
						(type none)
					)
				)
			)
			(symbol "R_470R_0402_1_1"
				(pin passive line
					(at 0 0 0)
					(length 0.635)
					(name "~"
						(effects
							(font
								(size 1.27 1.27)
							)
						)
					)
					(number "1"
						(effects
							(font
								(size 1.27 1.27)
							)
						)
					)
				)
				(pin passive line
					(at 5.08 0 180)
					(length 0.635)
					(name "~"
						(effects
							(font
								(size 1.27 1.27)
							)
						)
					)
					(number "2"
						(effects
							(font
								(size 1.27 1.27)
							)
						)
					)
				)
			)
		)
	(symbol "antmicroResistors0402:R_49R9_0402"
			(pin_numbers
				(hide yes)
			)
			(pin_names
				(hide yes)
			)
			(exclude_from_sim no)
			(in_bom yes)
			(on_board yes)
			(property "Reference" "R"
				(at 20.32 -5.08 0)
				(effects
					(font
						(size 1.27 1.27)
						(thickness 0.15)
					)
					(justify left bottom)
				)
			)
			(property "Value" "R_49R9_0402"
				(at 20.32 -12.7 0)
				(effects
					(font
						(size 1.27 1.27)
						(thickness 0.15)
					)
					(justify left bottom)
					(hide yes)
				)
			)
			(property "Footprint" "antmicro-footprints:R_0402_1005Metric"
				(at 20.32 -15.24 0)
				(effects
					(font
						(size 1.27 1.27)
						(thickness 0.15)
					)
					(justify left bottom)
					(hide yes)
				)
			)
			(property "Datasheet" "https://www.bourns.com/docs/product-datasheets/cr.pdf"
				(at 20.32 -17.78 0)
				(effects
					(font
						(size 1.27 1.27)
						(thickness 0.15)
					)
					(justify left bottom)
					(hide yes)
				)
			)
			(property "Description" "SMD Chip Resistor, 49.9 ohm, ± 1%, 62.5 mW, 0402 [1005 Metric], Thick Film, General Purpose"
				(at 0 0 0)
				(effects
					(font
						(size 1.27 1.27)
					)
					(hide yes)
				)
			)
			(property "MPN" "CR0402-FX-49R9GLF"
				(at 20.32 -20.32 0)
				(effects
					(font
						(size 1.27 1.27)
						(thickness 0.15)
					)
					(justify left bottom)
					(hide yes)
				)
			)
			(property "Manufacturer" "Bourns"
				(at 20.32 -22.86 0)
				(effects
					(font
						(size 1.27 1.27)
						(thickness 0.15)
					)
					(justify left bottom)
					(hide yes)
				)
			)
			(property "License" "Apache-2.0"
				(at 20.32 -25.4 0)
				(effects
					(font
						(size 1.27 1.27)
						(thickness 0.15)
					)
					(justify left bottom)
					(hide yes)
				)
			)
			(property "Author" "Antmicro"
				(at 20.32 -27.94 0)
				(effects
					(font
						(size 1.27 1.27)
						(thickness 0.15)
					)
					(justify left bottom)
					(hide yes)
				)
			)
			(property "Val" "49R9"
				(at 20.32 -7.62 0)
				(effects
					(font
						(size 1.27 1.27)
						(thickness 0.15)
					)
					(justify left bottom)
				)
			)
			(property "Tolerance" "1%"
				(at 20.32 -10.16 0)
				(effects
					(font
						(size 1.27 1.27)
					)
					(justify left bottom)
					(hide yes)
				)
			)
			(property "ki_keywords" "0402, SMT, RESISTOR, PASSIVE"
				(at 0 0 0)
				(effects
					(font
						(size 1.27 1.27)
					)
					(hide yes)
				)
			)
			(symbol "R_49R9_0402_0_1"
				(rectangle
					(start 0.635 0.889)
					(end 4.445 -0.889)
					(stroke
						(width 0.254)
						(type default)
					)
					(fill
						(type none)
					)
				)
			)
			(symbol "R_49R9_0402_1_1"
				(pin passive line
					(at 0 0 0)
					(length 0.635)
					(name "~"
						(effects
							(font
								(size 1.27 1.27)
							)
						)
					)
					(number "1"
						(effects
							(font
								(size 1.27 1.27)
							)
						)
					)
				)
				(pin passive line
					(at 5.08 0 180)
					(length 0.635)
					(name "~"
						(effects
							(font
								(size 1.27 1.27)
							)
						)
					)
					(number "2"
						(effects
							(font
								(size 1.27 1.27)
							)
						)
					)
				)
			)
		)
	(symbol "antmicroResistors0402:R_4k99_0402"
			(pin_numbers
				(hide yes)
			)
			(pin_names
				(hide yes)
			)
			(exclude_from_sim no)
			(in_bom yes)
			(on_board yes)
			(property "Reference" "R"
				(at 20.32 -5.08 0)
				(effects
					(font
						(size 1.27 1.27)
						(thickness 0.15)
					)
					(justify left bottom)
				)
			)
			(property "Value" "R_4k99_0402"
				(at 20.32 -12.7 0)
				(effects
					(font
						(size 1.27 1.27)
						(thickness 0.15)
					)
					(justify left bottom)
					(hide yes)
				)
			)
			(property "Footprint" "antmicro-footprints:R_0402_1005Metric"
				(at 20.32 -15.24 0)
				(effects
					(font
						(size 1.27 1.27)
						(thickness 0.15)
					)
					(justify left bottom)
					(hide yes)
				)
			)
			(property "Datasheet" "https://www.bourns.com/docs/product-datasheets/cr.pdf"
				(at 20.32 -17.78 0)
				(effects
					(font
						(size 1.27 1.27)
						(thickness 0.15)
					)
					(justify left bottom)
					(hide yes)
				)
			)
			(property "Description" "SMD Chip Resistor, 4.99 kohm, ± 1%, 62.5 mW, 0402 [1005 Metric], Thick Film, General Purpose"
				(at 0 0 0)
				(effects
					(font
						(size 1.27 1.27)
					)
					(hide yes)
				)
			)
			(property "MPN" "CR0402-FX-4991GLF"
				(at 20.32 -20.32 0)
				(effects
					(font
						(size 1.27 1.27)
						(thickness 0.15)
					)
					(justify left bottom)
					(hide yes)
				)
			)
			(property "Manufacturer" "Bourns"
				(at 20.32 -22.86 0)
				(effects
					(font
						(size 1.27 1.27)
						(thickness 0.15)
					)
					(justify left bottom)
					(hide yes)
				)
			)
			(property "License" "Apache-2.0"
				(at 20.32 -25.4 0)
				(effects
					(font
						(size 1.27 1.27)
						(thickness 0.15)
					)
					(justify left bottom)
					(hide yes)
				)
			)
			(property "Author" "Antmicro"
				(at 20.32 -27.94 0)
				(effects
					(font
						(size 1.27 1.27)
						(thickness 0.15)
					)
					(justify left bottom)
					(hide yes)
				)
			)
			(property "Val" "4k99"
				(at 20.32 -7.62 0)
				(effects
					(font
						(size 1.27 1.27)
						(thickness 0.15)
					)
					(justify left bottom)
				)
			)
			(property "Tolerance" "1%"
				(at 20.32 -10.16 0)
				(effects
					(font
						(size 1.27 1.27)
					)
					(justify left bottom)
					(hide yes)
				)
			)
			(property "ki_keywords" "0402, SMT, RESISTOR, PASSIVE"
				(at 0 0 0)
				(effects
					(font
						(size 1.27 1.27)
					)
					(hide yes)
				)
			)
			(symbol "R_4k99_0402_0_1"
				(rectangle
					(start 0.635 0.889)
					(end 4.445 -0.889)
					(stroke
						(width 0.254)
						(type default)
					)
					(fill
						(type none)
					)
				)
			)
			(symbol "R_4k99_0402_1_1"
				(pin passive line
					(at 0 0 0)
					(length 0.635)
					(name "~"
						(effects
							(font
								(size 1.27 1.27)
							)
						)
					)
					(number "1"
						(effects
							(font
								(size 1.27 1.27)
							)
						)
					)
				)
				(pin passive line
					(at 5.08 0 180)
					(length 0.635)
					(name "~"
						(effects
							(font
								(size 1.27 1.27)
							)
						)
					)
					(number "2"
						(effects
							(font
								(size 1.27 1.27)
							)
						)
					)
				)
			)
		)
	(symbol "antmicroResistors0402:R_5k1_0402"
			(pin_numbers
				(hide yes)
			)
			(pin_names
				(hide yes)
			)
			(exclude_from_sim no)
			(in_bom yes)
			(on_board yes)
			(property "Reference" "R"
				(at 20.32 -5.08 0)
				(effects
					(font
						(size 1.27 1.27)
						(thickness 0.15)
					)
					(justify left bottom)
				)
			)
			(property "Value" "R_5k1_0402"
				(at 20.32 -12.7 0)
				(effects
					(font
						(size 1.27 1.27)
						(thickness 0.15)
					)
					(justify left bottom)
					(hide yes)
				)
			)
			(property "Footprint" "antmicro-footprints:R_0402_1005Metric"
				(at 20.32 -15.24 0)
				(effects
					(font
						(size 1.27 1.27)
						(thickness 0.15)
					)
					(justify left bottom)
					(hide yes)
				)
			)
			(property "Datasheet" "https://www.bourns.com/docs/product-datasheets/cr.pdf"
				(at 20.32 -17.78 0)
				(effects
					(font
						(size 1.27 1.27)
						(thickness 0.15)
					)
					(justify left bottom)
					(hide yes)
				)
			)
			(property "Description" "SMD Chip Resistor, 5.1 kohm, ± 1%, 63 mW, 0402 [1005 Metric], Thick Film, General Purpose"
				(at 0 0 0)
				(effects
					(font
						(size 1.27 1.27)
					)
					(hide yes)
				)
			)
			(property "MPN" "CR0402-FX-5101GLF"
				(at 20.32 -20.32 0)
				(effects
					(font
						(size 1.27 1.27)
						(thickness 0.15)
					)
					(justify left bottom)
					(hide yes)
				)
			)
			(property "Manufacturer" "Bourns"
				(at 20.32 -22.86 0)
				(effects
					(font
						(size 1.27 1.27)
						(thickness 0.15)
					)
					(justify left bottom)
					(hide yes)
				)
			)
			(property "License" "Apache-2.0"
				(at 20.32 -25.4 0)
				(effects
					(font
						(size 1.27 1.27)
						(thickness 0.15)
					)
					(justify left bottom)
					(hide yes)
				)
			)
			(property "Author" "Antmicro"
				(at 20.32 -27.94 0)
				(effects
					(font
						(size 1.27 1.27)
						(thickness 0.15)
					)
					(justify left bottom)
					(hide yes)
				)
			)
			(property "Val" "5k1"
				(at 20.32 -7.62 0)
				(effects
					(font
						(size 1.27 1.27)
						(thickness 0.15)
					)
					(justify left bottom)
				)
			)
			(property "Tolerance" "1%"
				(at 20.32 -10.16 0)
				(effects
					(font
						(size 1.27 1.27)
					)
					(justify left bottom)
					(hide yes)
				)
			)
			(property "ki_keywords" "0402, SMT, RESISTOR, PASSIVE"
				(at 0 0 0)
				(effects
					(font
						(size 1.27 1.27)
					)
					(hide yes)
				)
			)
			(symbol "R_5k1_0402_0_1"
				(rectangle
					(start 0.635 0.889)
					(end 4.445 -0.889)
					(stroke
						(width 0.254)
						(type default)
					)
					(fill
						(type none)
					)
				)
			)
			(symbol "R_5k1_0402_1_1"
				(pin passive line
					(at 0 0 0)
					(length 0.635)
					(name "~"
						(effects
							(font
								(size 1.27 1.27)
							)
						)
					)
					(number "1"
						(effects
							(font
								(size 1.27 1.27)
							)
						)
					)
				)
				(pin passive line
					(at 5.08 0 180)
					(length 0.635)
					(name "~"
						(effects
							(font
								(size 1.27 1.27)
							)
						)
					)
					(number "2"
						(effects
							(font
								(size 1.27 1.27)
							)
						)
					)
				)
			)
		)
	(symbol "antmicroResistors0402:R_6k8_0402"
			(pin_numbers
				(hide yes)
			)
			(pin_names
				(hide yes)
			)
			(exclude_from_sim no)
			(in_bom yes)
			(on_board yes)
			(property "Reference" "R"
				(at 20.32 -5.08 0)
				(effects
					(font
						(size 1.27 1.27)
						(thickness 0.15)
					)
					(justify left bottom)
				)
			)
			(property "Value" "R_6k8_0402"
				(at 20.32 -12.7 0)
				(effects
					(font
						(size 1.27 1.27)
						(thickness 0.15)
					)
					(justify left bottom)
					(hide yes)
				)
			)
			(property "Footprint" "antmicro-footprints:R_0402_1005Metric"
				(at 20.32 -15.24 0)
				(effects
					(font
						(size 1.27 1.27)
						(thickness 0.15)
					)
					(justify left bottom)
					(hide yes)
				)
			)
			(property "Datasheet" "https://www.bourns.com/docs/product-datasheets/cr.pdf"
				(at 20.32 -17.78 0)
				(effects
					(font
						(size 1.27 1.27)
						(thickness 0.15)
					)
					(justify left bottom)
					(hide yes)
				)
			)
			(property "Description" "SMD Chip Resistor, 6.8 kohm, ± 1%, 63 mW, 0402 [1005 Metric], Thick Film, General Purpose"
				(at 0 0 0)
				(effects
					(font
						(size 1.27 1.27)
					)
					(hide yes)
				)
			)
			(property "MPN" "CR0402-FX-6801GLF"
				(at 20.32 -20.32 0)
				(effects
					(font
						(size 1.27 1.27)
						(thickness 0.15)
					)
					(justify left bottom)
					(hide yes)
				)
			)
			(property "Manufacturer" "Bourns"
				(at 20.32 -22.86 0)
				(effects
					(font
						(size 1.27 1.27)
						(thickness 0.15)
					)
					(justify left bottom)
					(hide yes)
				)
			)
			(property "License" "Apache-2.0"
				(at 20.32 -25.4 0)
				(effects
					(font
						(size 1.27 1.27)
						(thickness 0.15)
					)
					(justify left bottom)
					(hide yes)
				)
			)
			(property "Author" "Antmicro"
				(at 20.32 -27.94 0)
				(effects
					(font
						(size 1.27 1.27)
						(thickness 0.15)
					)
					(justify left bottom)
					(hide yes)
				)
			)
			(property "Val" "6k8"
				(at 20.32 -7.62 0)
				(effects
					(font
						(size 1.27 1.27)
						(thickness 0.15)
					)
					(justify left bottom)
				)
			)
			(property "Tolerance" "1%"
				(at 20.32 -10.16 0)
				(effects
					(font
						(size 1.27 1.27)
					)
					(justify left bottom)
					(hide yes)
				)
			)
			(property "ki_keywords" "0402, SMT, RESISTOR, PASSIVE"
				(at 0 0 0)
				(effects
					(font
						(size 1.27 1.27)
					)
					(hide yes)
				)
			)
			(symbol "R_6k8_0402_0_1"
				(rectangle
					(start 0.635 0.889)
					(end 4.445 -0.889)
					(stroke
						(width 0.254)
						(type default)
					)
					(fill
						(type none)
					)
				)
			)
			(symbol "R_6k8_0402_1_1"
				(pin passive line
					(at 0 0 0)
					(length 0.635)
					(name "~"
						(effects
							(font
								(size 1.27 1.27)
							)
						)
					)
					(number "1"
						(effects
							(font
								(size 1.27 1.27)
							)
						)
					)
				)
				(pin passive line
					(at 5.08 0 180)
					(length 0.635)
					(name "~"
						(effects
							(font
								(size 1.27 1.27)
							)
						)
					)
					(number "2"
						(effects
							(font
								(size 1.27 1.27)
							)
						)
					)
				)
			)
		)
	(symbol "antmicroResistors0402:R_80k6_0402"
			(pin_numbers
				(hide yes)
			)
			(pin_names
				(hide yes)
			)
			(exclude_from_sim no)
			(in_bom yes)
			(on_board yes)
			(property "Reference" "R"
				(at 20.32 -5.08 0)
				(effects
					(font
						(size 1.27 1.27)
						(thickness 0.15)
					)
					(justify left bottom)
				)
			)
			(property "Value" "R_80k6_0402"
				(at 20.32 -12.7 0)
				(effects
					(font
						(size 1.27 1.27)
						(thickness 0.15)
					)
					(justify left bottom)
					(hide yes)
				)
			)
			(property "Footprint" "antmicro-footprints:R_0402_1005Metric"
				(at 20.32 -15.24 0)
				(effects
					(font
						(size 1.27 1.27)
						(thickness 0.15)
					)
					(justify left bottom)
					(hide yes)
				)
			)
			(property "Datasheet" "https://www.bourns.com/docs/product-datasheets/cr.pdf"
				(at 20.32 -17.78 0)
				(effects
					(font
						(size 1.27 1.27)
						(thickness 0.15)
					)
					(justify left bottom)
					(hide yes)
				)
			)
			(property "Description" "SMD Chip Resistor, 80.6 kohm, ± 1%, 100 mW, 0402 [1005 Metric], Thick Film, Precision"
				(at 0 0 0)
				(effects
					(font
						(size 1.27 1.27)
					)
					(hide yes)
				)
			)
			(property "MPN" "CR0402-FX-8062GLF"
				(at 20.32 -20.32 0)
				(effects
					(font
						(size 1.27 1.27)
						(thickness 0.15)
					)
					(justify left bottom)
					(hide yes)
				)
			)
			(property "Manufacturer" "Bourns"
				(at 20.32 -22.86 0)
				(effects
					(font
						(size 1.27 1.27)
						(thickness 0.15)
					)
					(justify left bottom)
					(hide yes)
				)
			)
			(property "License" "Apache-2.0"
				(at 20.32 -25.4 0)
				(effects
					(font
						(size 1.27 1.27)
						(thickness 0.15)
					)
					(justify left bottom)
					(hide yes)
				)
			)
			(property "Author" "Antmicro"
				(at 20.32 -27.94 0)
				(effects
					(font
						(size 1.27 1.27)
						(thickness 0.15)
					)
					(justify left bottom)
					(hide yes)
				)
			)
			(property "Val" "80k6"
				(at 20.32 -7.62 0)
				(effects
					(font
						(size 1.27 1.27)
						(thickness 0.15)
					)
					(justify left bottom)
				)
			)
			(property "Tolerance" "1%"
				(at 20.32 -10.16 0)
				(effects
					(font
						(size 1.27 1.27)
					)
					(justify left bottom)
					(hide yes)
				)
			)
			(property "ki_keywords" "0402, SMT, RESISTOR, PASSIVE"
				(at 0 0 0)
				(effects
					(font
						(size 1.27 1.27)
					)
					(hide yes)
				)
			)
			(symbol "R_80k6_0402_0_1"
				(rectangle
					(start 0.635 0.889)
					(end 4.445 -0.889)
					(stroke
						(width 0.254)
						(type default)
					)
					(fill
						(type none)
					)
				)
			)
			(symbol "R_80k6_0402_1_1"
				(pin passive line
					(at 0 0 0)
					(length 0.635)
					(name "~"
						(effects
							(font
								(size 1.27 1.27)
							)
						)
					)
					(number "1"
						(effects
							(font
								(size 1.27 1.27)
							)
						)
					)
				)
				(pin passive line
					(at 5.08 0 180)
					(length 0.635)
					(name "~"
						(effects
							(font
								(size 1.27 1.27)
							)
						)
					)
					(number "2"
						(effects
							(font
								(size 1.27 1.27)
							)
						)
					)
				)
			)
		)
	(symbol "antmicroResistors0603:R_0R_22.4A_0603"
			(pin_numbers
				(hide yes)
			)
			(pin_names
				(hide yes)
			)
			(exclude_from_sim no)
			(in_bom yes)
			(on_board yes)
			(property "Reference" "R"
				(at 15.24 -2.54 0)
				(effects
					(font
						(size 1.27 1.27)
						(thickness 0.15)
					)
					(justify left bottom)
				)
			)
			(property "Value" "R_0R_22.4A_0603"
				(at 15.24 -5.08 0)
				(effects
					(font
						(size 1.27 1.27)
						(thickness 0.15)
					)
					(justify left bottom)
				)
			)
			(property "Footprint" "antmicro-footprints:R_0603_1608Metric"
				(at 15.24 -10.16 0)
				(effects
					(font
						(size 1.27 1.27)
						(thickness 0.15)
					)
					(justify left bottom)
					(hide yes)
				)
			)
			(property "Datasheet" "https://fscdn.rohm.com/en/products/databook/datasheet/passive/resistor/chip_resistor/pmr-jpw-e.pdf"
				(at 15.24 -12.7 0)
				(effects
					(font
						(size 1.27 1.27)
						(thickness 0.15)
					)
					(justify left bottom)
					(hide yes)
				)
			)
			(property "Description" "SMD Chip Resistor"
				(at 0 0 0)
				(effects
					(font
						(size 1.27 1.27)
					)
					(hide yes)
				)
			)
			(property "MPN" "PMR03EZPJ000"
				(at 15.24 -15.24 0)
				(effects
					(font
						(size 1.27 1.27)
						(thickness 0.15)
					)
					(justify left bottom)
					(hide yes)
				)
			)
			(property "Manufacturer" "ROHM Semiconductor"
				(at 15.24 -17.78 0)
				(effects
					(font
						(size 1.27 1.27)
						(thickness 0.15)
					)
					(justify left bottom)
					(hide yes)
				)
			)
			(property "Val" "0R"
				(at 15.24 -7.62 0)
				(effects
					(font
						(size 1.27 1.27)
						(thickness 0.15)
					)
					(justify left bottom)
				)
			)
			(property "Max. Curr." "22.4A"
				(at 15.24 -20.32 0)
				(effects
					(font
						(size 1.27 1.27)
						(thickness 0.15)
					)
					(justify left bottom)
				)
			)
			(property "Author" "Antmicro"
				(at 15.24 -22.86 0)
				(effects
					(font
						(size 1.27 1.27)
						(thickness 0.15)
					)
					(justify left bottom)
					(hide yes)
				)
			)
			(property "License" "Apache-2.0"
				(at 15.24 -25.4 0)
				(effects
					(font
						(size 1.27 1.27)
						(thickness 0.15)
					)
					(justify left bottom)
					(hide yes)
				)
			)
			(property "Tolerance" "template_tolerance"
				(at 20.32 -10.16 0)
				(effects
					(font
						(size 1.27 1.27)
					)
					(justify left bottom)
					(hide yes)
				)
			)
			(property "ki_keywords" "0603, SMT, RESISTOR, PASSIVE"
				(at 0 0 0)
				(effects
					(font
						(size 1.27 1.27)
					)
					(hide yes)
				)
			)
			(symbol "R_0R_22.4A_0603_0_1"
				(rectangle
					(start 0.635 0.889)
					(end 4.445 -0.889)
					(stroke
						(width 0.254)
						(type default)
					)
					(fill
						(type none)
					)
				)
			)
			(symbol "R_0R_22.4A_0603_1_1"
				(pin passive line
					(at 0 0 0)
					(length 0.635)
					(name "~"
						(effects
							(font
								(size 1.27 1.27)
							)
						)
					)
					(number "1"
						(effects
							(font
								(size 1.27 1.27)
							)
						)
					)
				)
				(pin passive line
					(at 5.08 0 180)
					(length 0.635)
					(name "~"
						(effects
							(font
								(size 1.27 1.27)
							)
						)
					)
					(number "2"
						(effects
							(font
								(size 1.27 1.27)
							)
						)
					)
				)
			)
		)
	(symbol "antmicroResonators:Resonator_25MHz_ABM8G"
			(pin_names
				(hide yes)
			)
			(exclude_from_sim no)
			(in_bom yes)
			(on_board yes)
			(property "Reference" "Y"
				(at 15.24 -5.08 0)
				(effects
					(font
						(size 1.27 1.27)
						(thickness 0.15)
					)
					(justify left bottom)
				)
			)
			(property "Value" "Resonator_25MHz_ABM8G"
				(at 15.24 -12.7 0)
				(effects
					(font
						(size 1.27 1.27)
						(thickness 0.15)
					)
					(justify left bottom)
					(hide yes)
				)
			)
			(property "Footprint" "antmicro-footprints:Resonator_SMD_Abracon_ABM8G_3.2x2.5mm"
				(at 15.24 -15.24 0)
				(effects
					(font
						(size 1.27 1.27)
						(thickness 0.15)
					)
					(justify left bottom)
					(hide yes)
				)
			)
			(property "Datasheet" "https://abracon.com/Resonators/ABM8G.pdf"
				(at 15.24 -17.78 0)
				(effects
					(font
						(size 1.27 1.27)
						(thickness 0.15)
					)
					(justify left bottom)
					(hide yes)
				)
			)
			(property "Description" "Crystal, 25 MHz, SMD, 3.2mm x 2.5mm, 30 ppm, 18 pF, 20 ppm, ABM8G"
				(at 0 0 0)
				(effects
					(font
						(size 1.27 1.27)
					)
					(hide yes)
				)
			)
			(property "MPN" "ABM8G-25.000MHZ-18-D2Y-T3"
				(at 15.24 -7.62 0)
				(effects
					(font
						(size 1.27 1.27)
						(thickness 0.15)
					)
					(justify left bottom)
				)
			)
			(property "Manufacturer" "Abracon"
				(at 15.24 -20.32 0)
				(effects
					(font
						(size 1.27 1.27)
						(thickness 0.15)
					)
					(justify left bottom)
					(hide yes)
				)
			)
			(property "Author" "Antmicro"
				(at 15.24 -22.86 0)
				(effects
					(font
						(size 1.27 1.27)
						(thickness 0.15)
					)
					(justify left bottom)
					(hide yes)
				)
			)
			(property "License" "Apache-2.0"
				(at 15.24 -25.4 0)
				(effects
					(font
						(size 1.27 1.27)
						(thickness 0.15)
					)
					(justify left bottom)
					(hide yes)
				)
			)
			(property "Val" "25 MHz"
				(at 15.24 -10.16 0)
				(effects
					(font
						(size 1.27 1.27)
						(thickness 0.15)
					)
					(justify left bottom)
				)
			)
			(property "ki_keywords" "SMT, CERAMIC, OSCILLATOR"
				(at 0 0 0)
				(effects
					(font
						(size 1.27 1.27)
					)
					(hide yes)
				)
			)
			(symbol "Resonator_25MHz_ABM8G_1_1"
				(polyline
					(pts
						(xy 1.905 1.905) (xy 1.905 2.54) (xy 5.715 2.54) (xy 5.715 1.905)
					)
					(stroke
						(width 0.254)
						(type default)
					)
					(fill
						(type none)
					)
				)
				(polyline
					(pts
						(xy 1.905 -1.905) (xy 1.905 -2.54) (xy 5.715 -2.54) (xy 5.715 -1.905)
					)
					(stroke
						(width 0.254)
						(type default)
					)
					(fill
						(type none)
					)
				)
				(polyline
					(pts
						(xy 2.54 1.27) (xy 2.54 -1.27)
					)
					(stroke
						(width 0.254)
						(type default)
					)
					(fill
						(type background)
					)
				)
				(rectangle
					(start 3.175 1.905)
					(end 4.445 -1.905)
					(stroke
						(width 0.254)
						(type default)
					)
					(fill
						(type background)
					)
				)
				(polyline
					(pts
						(xy 5.08 1.27) (xy 5.08 -1.27)
					)
					(stroke
						(width 0.254)
						(type default)
					)
					(fill
						(type background)
					)
				)
				(pin passive line
					(at 0 0 0)
					(length 2.54)
					(name "~"
						(effects
							(font
								(size 1.27 1.27)
							)
						)
					)
					(number "1"
						(effects
							(font
								(size 1.27 1.27)
							)
						)
					)
				)
				(pin passive line
					(at 3.81 -5.08 90)
					(length 2.54)
					(name "SH"
						(effects
							(font
								(size 1.27 1.27)
							)
						)
					)
					(number "2"
						(effects
							(font
								(size 1.27 1.27)
							)
						)
					)
				)
				(pin passive line
					(at 3.81 -5.08 90)
					(length 2.54)
					(hide yes)
					(name "SH"
						(effects
							(font
								(size 1.27 1.27)
							)
						)
					)
					(number "4"
						(effects
							(font
								(size 1.27 1.27)
							)
						)
					)
				)
				(pin passive line
					(at 7.62 0 180)
					(length 2.54)
					(name "~"
						(effects
							(font
								(size 1.27 1.27)
							)
						)
					)
					(number "3"
						(effects
							(font
								(size 1.27 1.27)
							)
						)
					)
				)
			)
		)
	(symbol "antmicroTVSDiodes:ESD5B5_0ST1G"
			(pin_numbers
				(hide yes)
			)
			(pin_names
				(hide yes)
			)
			(exclude_from_sim no)
			(in_bom yes)
			(on_board yes)
			(property "Reference" "D"
				(at 25.4 -5.08 0)
				(effects
					(font
						(size 1.27 1.27)
						(thickness 0.15)
					)
					(justify left bottom)
				)
			)
			(property "Value" "ESD5B5_0ST1G"
				(at 25.4 -17.78 0)
				(effects
					(font
						(size 1.27 1.27)
						(thickness 0.15)
					)
					(justify left bottom)
					(hide yes)
				)
			)
			(property "Footprint" "antmicro-footprints:SOD-523_NP"
				(at 25.4 -10.16 0)
				(effects
					(font
						(size 1.27 1.27)
						(thickness 0.15)
					)
					(justify left bottom)
					(hide yes)
				)
			)
			(property "Datasheet" "https://www.onsemi.com/pdf/datasheet/esd5b5.0st1-d.pdf"
				(at 25.4 -12.7 0)
				(effects
					(font
						(size 1.27 1.27)
						(thickness 0.15)
					)
					(justify left bottom)
					(hide yes)
				)
			)
			(property "Description" "Bidirectional TVS, 30 kV,  SOD-523, 5 V, 32 pF"
				(at 0 0 0)
				(effects
					(font
						(size 1.27 1.27)
					)
					(hide yes)
				)
			)
			(property "Manufacturer" "ON Semiconductor"
				(at 25.4 -15.24 0)
				(effects
					(font
						(size 1.27 1.27)
						(thickness 0.15)
					)
					(justify left bottom)
					(hide yes)
				)
			)
			(property "MPN" "ESD5B5.0ST1G"
				(at 25.4 -7.62 0)
				(effects
					(font
						(size 1.27 1.27)
						(thickness 0.15)
					)
					(justify left bottom)
				)
			)
			(property "Author" "Antmicro"
				(at 25.4 -20.32 0)
				(effects
					(font
						(size 1.27 1.27)
						(thickness 0.15)
					)
					(justify left bottom)
					(hide yes)
				)
			)
			(property "License" "Apache-2.0"
				(at 25.4 -22.86 0)
				(effects
					(font
						(size 1.27 1.27)
						(thickness 0.15)
					)
					(justify left bottom)
					(hide yes)
				)
			)
			(property "ki_keywords" "DIODE, SEMICONDUCTOR, TVS, ESD"
				(at 0 0 0)
				(effects
					(font
						(size 1.27 1.27)
					)
					(hide yes)
				)
			)
			(symbol "ESD5B5_0ST1G_0_0"
				(text ""
					(at 7.62 -1.27 0)
					(effects
						(font
							(size 1.27 1.27)
						)
					)
				)
			)
			(symbol "ESD5B5_0ST1G_0_1"
				(polyline
					(pts
						(xy 0.635 0) (xy 4.445 0)
					)
					(stroke
						(width 0)
						(type default)
					)
					(fill
						(type none)
					)
				)
			)
			(symbol "ESD5B5_0ST1G_1_1"
				(polyline
					(pts
						(xy 1.016 -1.016) (xy 1.016 1.016) (xy 2.54 0) (xy 1.016 -1.016)
					)
					(stroke
						(width 0.254)
						(type default)
					)
					(fill
						(type outline)
					)
				)
				(polyline
					(pts
						(xy 2.54 1.016) (xy 2.159 1.016)
					)
					(stroke
						(width 0.254)
						(type default)
					)
					(fill
						(type none)
					)
				)
				(polyline
					(pts
						(xy 2.54 1.016) (xy 2.54 -1.016)
					)
					(stroke
						(width 0.254)
						(type default)
					)
					(fill
						(type none)
					)
				)
				(polyline
					(pts
						(xy 2.921 -1.016) (xy 2.54 -1.016)
					)
					(stroke
						(width 0.254)
						(type default)
					)
					(fill
						(type none)
					)
				)
				(polyline
					(pts
						(xy 4.064 1.016) (xy 4.064 -1.016) (xy 2.54 0) (xy 4.064 1.016)
					)
					(stroke
						(width 0.254)
						(type default)
					)
					(fill
						(type outline)
					)
				)
				(pin passive line
					(at 0 0 0)
					(length 0.635)
					(name "C"
						(effects
							(font
								(size 1.27 1.27)
							)
						)
					)
					(number "1"
						(effects
							(font
								(size 1.27 1.27)
							)
						)
					)
				)
				(pin passive line
					(at 5.08 0 180)
					(length 0.635)
					(name "A"
						(effects
							(font
								(size 1.27 1.27)
							)
						)
					)
					(number "2"
						(effects
							(font
								(size 1.27 1.27)
							)
						)
					)
				)
			)
		)
	(symbol "antmicroTVSDiodes:PESD4USB5U-TTS"
			(pin_names
				(hide yes)
			)
			(exclude_from_sim no)
			(in_bom yes)
			(on_board yes)
			(property "Reference" "D"
				(at 13.97 4.445 0)
				(effects
					(font
						(size 1.27 1.27)
						(thickness 0.15)
					)
					(justify left bottom)
				)
			)
			(property "Value" "PESD4USB5U-TTS"
				(at 13.97 -5.715 0)
				(effects
					(font
						(size 1.27 1.27)
						(thickness 0.15)
					)
					(justify left bottom)
					(hide yes)
				)
			)
			(property "Footprint" "antmicro-footprints:DFN-10_2.5x1mm"
				(at 13.97 -0.635 0)
				(effects
					(font
						(size 1.27 1.27)
						(thickness 0.15)
					)
					(justify left bottom)
					(hide yes)
				)
			)
			(property "Datasheet" "https://assets.nexperia.com/documents/data-sheet/PESD4USB5U-TTS.pdf"
				(at 13.97 -3.175 0)
				(effects
					(font
						(size 1.27 1.27)
						(thickness 0.15)
					)
					(justify left bottom)
					(hide yes)
				)
			)
			(property "Description" "TVS diode array, 15kV, DFN-10, 5 V, 0.5 pF"
				(at 0 0 0)
				(effects
					(font
						(size 1.27 1.27)
					)
					(hide yes)
				)
			)
			(property "MPN" "PESD4USB5U-TTS"
				(at 13.97 1.905 0)
				(effects
					(font
						(size 1.27 1.27)
						(thickness 0.15)
					)
					(justify left bottom)
				)
			)
			(property "Manufacturer" "Nexperia"
				(at 13.97 -8.255 0)
				(effects
					(font
						(size 1.27 1.27)
						(thickness 0.15)
					)
					(justify left bottom)
					(hide yes)
				)
			)
			(property "Author" "Antmicro"
				(at 13.97 -10.795 0)
				(effects
					(font
						(size 1.27 1.27)
						(thickness 0.15)
					)
					(justify left bottom)
					(hide yes)
				)
			)
			(property "License" "Apache-2.0"
				(at 13.97 -13.335 0)
				(effects
					(font
						(size 1.27 1.27)
						(thickness 0.15)
					)
					(justify left bottom)
					(hide yes)
				)
			)
			(property "ki_keywords" "SMT, DIODE, SEMICONDUCTOR, TVS, ESD"
				(at 0 0 0)
				(effects
					(font
						(size 1.27 1.27)
					)
					(hide yes)
				)
			)
			(symbol "PESD4USB5U-TTS_0_1"
				(polyline
					(pts
						(xy 2.54 -10.16) (xy 6.35 -10.16) (xy 6.35 0) (xy 5.08 0)
					)
					(stroke
						(width 0.254)
						(type default)
					)
					(fill
						(type none)
					)
				)
				(polyline
					(pts
						(xy 3.81 0) (xy 2.54 0)
					)
					(stroke
						(width 0.254)
						(type default)
					)
					(fill
						(type none)
					)
				)
				(polyline
					(pts
						(xy 3.81 -2.54) (xy 2.54 -2.54)
					)
					(stroke
						(width 0.254)
						(type default)
					)
					(fill
						(type none)
					)
				)
				(polyline
					(pts
						(xy 3.81 -5.08) (xy 2.54 -5.08)
					)
					(stroke
						(width 0.254)
						(type default)
					)
					(fill
						(type none)
					)
				)
				(polyline
					(pts
						(xy 3.81 -7.62) (xy 2.54 -7.62)
					)
					(stroke
						(width 0.254)
						(type default)
					)
					(fill
						(type none)
					)
				)
				(polyline
					(pts
						(xy 5.08 -2.54) (xy 6.35 -2.54)
					)
					(stroke
						(width 0.254)
						(type default)
					)
					(fill
						(type none)
					)
				)
				(polyline
					(pts
						(xy 5.08 -5.08) (xy 6.35 -5.08)
					)
					(stroke
						(width 0.254)
						(type default)
					)
					(fill
						(type none)
					)
				)
				(polyline
					(pts
						(xy 5.08 -7.62) (xy 6.35 -7.62)
					)
					(stroke
						(width 0.254)
						(type default)
					)
					(fill
						(type none)
					)
				)
			)
			(symbol "PESD4USB5U-TTS_1_1"
				(rectangle
					(start 2.54 1.27)
					(end 7.62 -11.43)
					(stroke
						(width 0.254)
						(type default)
					)
					(fill
						(type background)
					)
				)
				(polyline
					(pts
						(xy 3.81 -0.635) (xy 3.81 -0.381) (xy 3.81 0.381) (xy 4.064 0.635)
					)
					(stroke
						(width 0.254)
						(type default)
					)
					(fill
						(type background)
					)
				)
				(polyline
					(pts
						(xy 3.81 -3.175) (xy 3.81 -2.921) (xy 3.81 -2.159) (xy 4.064 -1.905)
					)
					(stroke
						(width 0.254)
						(type default)
					)
					(fill
						(type background)
					)
				)
				(polyline
					(pts
						(xy 3.81 -5.715) (xy 3.81 -5.461) (xy 3.81 -4.699) (xy 4.064 -4.445)
					)
					(stroke
						(width 0.254)
						(type default)
					)
					(fill
						(type background)
					)
				)
				(polyline
					(pts
						(xy 3.81 -8.255) (xy 3.81 -8.001) (xy 3.81 -7.239) (xy 4.064 -6.985)
					)
					(stroke
						(width 0.254)
						(type default)
					)
					(fill
						(type background)
					)
				)
				(polyline
					(pts
						(xy 5.08 -0.635) (xy 5.08 0.635) (xy 3.81 0) (xy 5.08 -0.635)
					)
					(stroke
						(width 0.254)
						(type default)
					)
					(fill
						(type outline)
					)
				)
				(polyline
					(pts
						(xy 5.08 -3.175) (xy 5.08 -1.905) (xy 3.81 -2.54) (xy 5.08 -3.175)
					)
					(stroke
						(width 0.254)
						(type default)
					)
					(fill
						(type outline)
					)
				)
				(polyline
					(pts
						(xy 5.08 -5.715) (xy 5.08 -4.445) (xy 3.81 -5.08) (xy 5.08 -5.715)
					)
					(stroke
						(width 0.254)
						(type default)
					)
					(fill
						(type outline)
					)
				)
				(polyline
					(pts
						(xy 5.08 -8.255) (xy 5.08 -6.985) (xy 3.81 -7.62) (xy 5.08 -8.255)
					)
					(stroke
						(width 0.254)
						(type default)
					)
					(fill
						(type outline)
					)
				)
				(circle
					(center 6.35 -2.54)
					(radius 0.127)
					(stroke
						(width 0.254)
						(type default)
					)
					(fill
						(type background)
					)
				)
				(circle
					(center 6.35 -5.08)
					(radius 0.127)
					(stroke
						(width 0.254)
						(type default)
					)
					(fill
						(type background)
					)
				)
				(circle
					(center 6.35 -7.62)
					(radius 0.127)
					(stroke
						(width 0.254)
						(type default)
					)
					(fill
						(type background)
					)
				)
				(pin passive line
					(at 0 0 0)
					(length 2.54)
					(name "1"
						(effects
							(font
								(size 1.27 1.27)
							)
						)
					)
					(number "1"
						(effects
							(font
								(size 1.27 1.27)
							)
						)
					)
				)
				(pin passive line
					(at 0 0 0)
					(length 2.54)
					(hide yes)
					(name "10"
						(effects
							(font
								(size 1.27 1.27)
							)
						)
					)
					(number "10"
						(effects
							(font
								(size 1.27 1.27)
							)
						)
					)
				)
				(pin passive line
					(at 0 -2.54 0)
					(length 2.54)
					(name "2"
						(effects
							(font
								(size 1.27 1.27)
							)
						)
					)
					(number "2"
						(effects
							(font
								(size 1.27 1.27)
							)
						)
					)
				)
				(pin passive line
					(at 0 -2.54 0)
					(length 2.54)
					(hide yes)
					(name "9"
						(effects
							(font
								(size 1.27 1.27)
							)
						)
					)
					(number "9"
						(effects
							(font
								(size 1.27 1.27)
							)
						)
					)
				)
				(pin passive line
					(at 0 -5.08 0)
					(length 2.54)
					(name "4"
						(effects
							(font
								(size 1.27 1.27)
							)
						)
					)
					(number "4"
						(effects
							(font
								(size 1.27 1.27)
							)
						)
					)
				)
				(pin passive line
					(at 0 -5.08 0)
					(length 2.54)
					(hide yes)
					(name "7"
						(effects
							(font
								(size 1.27 1.27)
							)
						)
					)
					(number "7"
						(effects
							(font
								(size 1.27 1.27)
							)
						)
					)
				)
				(pin passive line
					(at 0 -7.62 0)
					(length 2.54)
					(name "5"
						(effects
							(font
								(size 1.27 1.27)
							)
						)
					)
					(number "5"
						(effects
							(font
								(size 1.27 1.27)
							)
						)
					)
				)
				(pin passive line
					(at 0 -7.62 0)
					(length 2.54)
					(hide yes)
					(name "6"
						(effects
							(font
								(size 1.27 1.27)
							)
						)
					)
					(number "6"
						(effects
							(font
								(size 1.27 1.27)
							)
						)
					)
				)
				(pin passive line
					(at 0 -10.16 0)
					(length 2.54)
					(name "3"
						(effects
							(font
								(size 1.27 1.27)
							)
						)
					)
					(number "3"
						(effects
							(font
								(size 1.27 1.27)
							)
						)
					)
				)
				(pin passive line
					(at 0 -10.16 0)
					(length 2.54)
					(hide yes)
					(name "8"
						(effects
							(font
								(size 1.27 1.27)
							)
						)
					)
					(number "8"
						(effects
							(font
								(size 1.27 1.27)
							)
						)
					)
				)
			)
		)
	(symbol "antmicroTVSDiodes:SMF4L15A"
			(pin_numbers
				(hide yes)
			)
			(pin_names
				(hide yes)
			)
			(exclude_from_sim no)
			(in_bom yes)
			(on_board yes)
			(property "Reference" "D"
				(at 26.67 -5.08 0)
				(effects
					(font
						(size 1.27 1.27)
						(thickness 0.15)
					)
					(justify left bottom)
				)
			)
			(property "Value" "SMF4L15A"
				(at 26.67 -15.24 0)
				(effects
					(font
						(size 1.27 1.27)
						(thickness 0.15)
					)
					(justify left bottom)
					(hide yes)
				)
			)
			(property "Footprint" "antmicro-footprints:SOD-123FL"
				(at 26.67 -10.16 0)
				(effects
					(font
						(size 1.27 1.27)
						(thickness 0.15)
					)
					(justify left bottom)
					(hide yes)
				)
			)
			(property "Datasheet" "https://www.littelfuse.com/media?resourcetype=datasheets&itemid=d2ba8fab-1de3-4176-8530-f36ecb0b8799&filename=smf4l"
				(at 26.67 -12.7 0)
				(effects
					(font
						(size 1.27 1.27)
						(thickness 0.15)
					)
					(justify left bottom)
					(hide yes)
				)
			)
			(property "Description" "Unidirectional TVS, 30 kV,  SOD-123FL, 15 V, 600 pF"
				(at 0 0 0)
				(effects
					(font
						(size 1.27 1.27)
					)
					(hide yes)
				)
			)
			(property "MPN" "SMF4L15A"
				(at 26.67 -7.62 0)
				(effects
					(font
						(size 1.27 1.27)
						(thickness 0.15)
					)
					(justify left bottom)
				)
			)
			(property "Manufacturer" "Littelfuse"
				(at 26.67 -17.78 0)
				(effects
					(font
						(size 1.27 1.27)
						(thickness 0.15)
					)
					(justify left bottom)
					(hide yes)
				)
			)
			(property "Author" "Antmicro"
				(at 26.67 -20.32 0)
				(effects
					(font
						(size 1.27 1.27)
						(thickness 0.15)
					)
					(justify left bottom)
					(hide yes)
				)
			)
			(property "License" "Apache-2.0"
				(at 26.67 -22.86 0)
				(effects
					(font
						(size 1.27 1.27)
						(thickness 0.15)
					)
					(justify left bottom)
					(hide yes)
				)
			)
			(property "ki_keywords" "DIODE, SEMICONDUCTOR, TVS, ESD"
				(at 0 0 0)
				(effects
					(font
						(size 1.27 1.27)
					)
					(hide yes)
				)
			)
			(symbol "SMF4L15A_0_1"
				(polyline
					(pts
						(xy 1.905 0) (xy 0.635 0)
					)
					(stroke
						(width 0)
						(type default)
					)
					(fill
						(type none)
					)
				)
				(polyline
					(pts
						(xy 4.445 0) (xy 3.175 0)
					)
					(stroke
						(width 0)
						(type default)
					)
					(fill
						(type none)
					)
				)
			)
			(symbol "SMF4L15A_1_1"
				(polyline
					(pts
						(xy 1.778 1.016) (xy 1.397 1.016)
					)
					(stroke
						(width 0.254)
						(type default)
					)
					(fill
						(type none)
					)
				)
				(polyline
					(pts
						(xy 1.778 1.016) (xy 1.778 -1.016)
					)
					(stroke
						(width 0.254)
						(type default)
					)
					(fill
						(type none)
					)
				)
				(polyline
					(pts
						(xy 2.159 -1.016) (xy 1.778 -1.016)
					)
					(stroke
						(width 0.254)
						(type default)
					)
					(fill
						(type none)
					)
				)
				(polyline
					(pts
						(xy 3.302 1.016) (xy 3.302 -1.016) (xy 1.778 0) (xy 3.302 1.016)
					)
					(stroke
						(width 0.254)
						(type default)
					)
					(fill
						(type outline)
					)
				)
				(pin passive line
					(at 0 0 0)
					(length 0.635)
					(name "C"
						(effects
							(font
								(size 1.27 1.27)
							)
						)
					)
					(number "1"
						(effects
							(font
								(size 1.27 1.27)
							)
						)
					)
				)
				(pin passive line
					(at 5.08 0 180)
					(length 0.635)
					(name "A"
						(effects
							(font
								(size 1.27 1.27)
							)
						)
					)
					(number "2"
						(effects
							(font
								(size 1.27 1.27)
							)
						)
					)
				)
			)
		)
	(symbol "antmicroTestPoints:TP_0.75mm_SMD"
			(pin_names
				(hide yes)
			)
			(exclude_from_sim no)
			(in_bom no)
			(on_board yes)
			(property "Reference" "TP"
				(at 10.16 -1.27 0)
				(effects
					(font
						(size 1.27 1.27)
						(thickness 0.15)
					)
					(justify left bottom)
				)
			)
			(property "Value" "TP_0.75mm_SMD"
				(at 10.16 -3.81 0)
				(effects
					(font
						(size 1.27 1.27)
						(thickness 0.15)
					)
					(justify left bottom)
					(hide yes)
				)
			)
			(property "Footprint" "antmicro-footprints:TP_SMD_0.75mm"
				(at 10.16 -6.35 0)
				(effects
					(font
						(size 1.27 1.27)
						(thickness 0.15)
					)
					(justify left bottom)
					(hide yes)
				)
			)
			(property "Datasheet" ""
				(at 17.78 -12.7 0)
				(effects
					(font
						(size 1.27 1.27)
						(thickness 0.15)
					)
					(justify left bottom)
					(hide yes)
				)
			)
			(property "Description" "SMT test point"
				(at 0 0 0)
				(effects
					(font
						(size 1.27 1.27)
					)
					(hide yes)
				)
			)
			(property "MPN" ""
				(at 10.795 -11.43 0)
				(effects
					(font
						(size 1.27 1.27)
						(thickness 0.15)
					)
					(justify left bottom)
					(hide yes)
				)
			)
			(property "Manufacturer" ""
				(at 10.795 -6.35 0)
				(effects
					(font
						(size 1.27 1.27)
						(thickness 0.15)
					)
					(justify left bottom)
					(hide yes)
				)
			)
			(property "Author" "Antmicro"
				(at 10.16 -8.89 0)
				(effects
					(font
						(size 1.27 1.27)
						(thickness 0.15)
					)
					(justify left bottom)
					(hide yes)
				)
			)
			(property "License" "Apache-2.0"
				(at 10.16 -11.43 0)
				(effects
					(font
						(size 1.27 1.27)
						(thickness 0.15)
					)
					(justify left bottom)
					(hide yes)
				)
			)
			(property "ki_keywords" "TESTPOINT"
				(at 0 0 0)
				(effects
					(font
						(size 1.27 1.27)
					)
					(hide yes)
				)
			)
			(symbol "TP_0.75mm_SMD_1_1"
				(circle
					(center 3.175 0)
					(radius 0.635)
					(stroke
						(width 0.254)
						(type default)
					)
					(fill
						(type none)
					)
				)
				(pin passive line
					(at 0 0 0)
					(length 2.54)
					(name "1"
						(effects
							(font
								(size 1.27 1.27)
							)
						)
					)
					(number "1"
						(effects
							(font
								(size 1.27 1.27)
							)
						)
					)
				)
			)
		)
	(symbol "antmicroTransistorsFETsMOSFETsSingle:BSS138AKA"
			(pin_names
				(offset 0)
			)
			(exclude_from_sim no)
			(in_bom no)
			(on_board yes)
			(property "Reference" "Q"
				(at 15.24 -2.54 0)
				(effects
					(font
						(size 1.27 1.27)
						(thickness 0.15)
					)
					(justify left bottom)
				)
			)
			(property "Value" "BSS138AKA"
				(at 15.24 -7.62 0)
				(effects
					(font
						(size 1.27 1.27)
						(thickness 0.15)
					)
					(justify left bottom)
					(hide yes)
				)
			)
			(property "Footprint" "antmicro-footprints:SOT-23-3"
				(at 15.24 -12.7 0)
				(effects
					(font
						(size 1.27 1.27)
						(thickness 0.15)
					)
					(justify left bottom)
					(hide yes)
				)
			)
			(property "Datasheet" "https://www.onsemi.com/pub/Collateral/BSS138-D.PDF"
				(at 15.24 -15.24 0)
				(effects
					(font
						(size 1.27 1.27)
						(thickness 0.15)
					)
					(justify left bottom)
					(hide yes)
				)
			)
			(property "Description" "Power MOSFET, N Channel, 50 V, 220 mA, 6.0 ohm, SOT-23, Surface Mount"
				(at 52.324 -21.844 0)
				(effects
					(font
						(size 1.27 1.27)
					)
					(hide yes)
				)
			)
			(property "MPN" "BSS138AKA"
				(at 15.24 -5.08 0)
				(effects
					(font
						(size 1.27 1.27)
						(thickness 0.15)
					)
					(justify left bottom)
				)
			)
			(property "Manufacturer" "ON Semiconductor"
				(at 15.24 -10.16 0)
				(effects
					(font
						(size 1.27 1.27)
						(thickness 0.15)
					)
					(justify left bottom)
					(hide yes)
				)
			)
			(property "Author" "Antmicro"
				(at 15.24 -17.78 0)
				(effects
					(font
						(size 1.27 1.27)
						(thickness 0.15)
					)
					(justify left bottom)
					(hide yes)
				)
			)
			(property "License" "Apache-2.0"
				(at 15.24 -20.32 0)
				(effects
					(font
						(size 1.27 1.27)
						(thickness 0.15)
					)
					(justify left bottom)
					(hide yes)
				)
			)
			(property "ki_keywords" "SMT, TRANSISTOR, SEMICONDUCTOR, NMOS"
				(at 0 0 0)
				(effects
					(font
						(size 1.27 1.27)
					)
					(hide yes)
				)
			)
			(symbol "BSS138AKA_1_1"
				(polyline
					(pts
						(xy 1.27 0) (xy 3.302 0) (xy 3.302 3.937)
					)
					(stroke
						(width 0.254)
						(type default)
					)
					(fill
						(type none)
					)
				)
				(polyline
					(pts
						(xy 3.81 4.445) (xy 3.81 3.429)
					)
					(stroke
						(width 0.254)
						(type default)
					)
					(fill
						(type background)
					)
				)
				(polyline
					(pts
						(xy 3.81 2.54) (xy 3.81 3.048)
					)
					(stroke
						(width 0.254)
						(type default)
					)
					(fill
						(type background)
					)
				)
				(polyline
					(pts
						(xy 3.81 2.54) (xy 3.81 2.032)
					)
					(stroke
						(width 0.254)
						(type default)
					)
					(fill
						(type background)
					)
				)
				(polyline
					(pts
						(xy 3.81 2.54) (xy 4.572 3.048) (xy 4.572 2.032) (xy 3.81 2.54)
					)
					(stroke
						(width 0.254)
						(type default)
					)
					(fill
						(type outline)
					)
				)
				(polyline
					(pts
						(xy 3.81 1.143) (xy 3.81 1.651)
					)
					(stroke
						(width 0.254)
						(type default)
					)
					(fill
						(type background)
					)
				)
				(polyline
					(pts
						(xy 3.81 1.143) (xy 3.81 0.635)
					)
					(stroke
						(width 0.254)
						(type default)
					)
					(fill
						(type background)
					)
				)
				(circle
					(center 5.08 2.54)
					(radius 3.302)
					(stroke
						(width 0.254)
						(type default)
					)
					(fill
						(type background)
					)
				)
				(polyline
					(pts
						(xy 6.223 0.635) (xy 7.366 0.635) (xy 7.366 3.937) (xy 7.366 4.445) (xy 6.223 4.445)
					)
					(stroke
						(width 0.254)
						(type default)
					)
					(fill
						(type none)
					)
				)
				(polyline
					(pts
						(xy 6.35 6.35) (xy 6.35 3.937) (xy 3.81 3.937)
					)
					(stroke
						(width 0.254)
						(type default)
					)
					(fill
						(type none)
					)
				)
				(circle
					(center 6.35 4.445)
					(radius 0.127)
					(stroke
						(width 0.254)
						(type default)
					)
					(fill
						(type background)
					)
				)
				(polyline
					(pts
						(xy 6.35 1.143) (xy 3.81 1.143)
					)
					(stroke
						(width 0.254)
						(type default)
					)
					(fill
						(type background)
					)
				)
				(circle
					(center 6.35 1.143)
					(radius 0.127)
					(stroke
						(width 0.254)
						(type default)
					)
					(fill
						(type background)
					)
				)
				(circle
					(center 6.35 0.635)
					(radius 0.127)
					(stroke
						(width 0.254)
						(type default)
					)
					(fill
						(type background)
					)
				)
				(polyline
					(pts
						(xy 6.35 -1.27) (xy 6.35 2.54) (xy 3.81 2.54)
					)
					(stroke
						(width 0.254)
						(type default)
					)
					(fill
						(type none)
					)
				)
				(polyline
					(pts
						(xy 7.366 3.048) (xy 6.858 2.286) (xy 7.874 2.286) (xy 7.366 3.048)
					)
					(stroke
						(width 0.254)
						(type default)
					)
					(fill
						(type outline)
					)
				)
				(polyline
					(pts
						(xy 7.874 3.048) (xy 6.858 3.048)
					)
					(stroke
						(width 0.254)
						(type default)
					)
					(fill
						(type background)
					)
				)
				(pin input line
					(at 0 0 0)
					(length 2.54)
					(name "G"
						(effects
							(font
								(size 1.27 1.27)
							)
						)
					)
					(number "1"
						(effects
							(font
								(size 1.27 1.27)
							)
						)
					)
				)
				(pin passive line
					(at 6.35 7.62 270)
					(length 2.54)
					(name "D"
						(effects
							(font
								(size 1.27 1.27)
							)
						)
					)
					(number "3"
						(effects
							(font
								(size 1.27 1.27)
							)
						)
					)
				)
				(pin passive line
					(at 6.35 -2.54 90)
					(length 2.54)
					(name "S"
						(effects
							(font
								(size 1.27 1.27)
							)
						)
					)
					(number "2"
						(effects
							(font
								(size 1.27 1.27)
							)
						)
					)
				)
			)
		)
	(symbol "antmicroTransistorsFETsMOSFETsSingle:DMG1012T-7"
			(pin_names
				(offset 0)
			)
			(exclude_from_sim no)
			(in_bom no)
			(on_board yes)
			(property "Reference" "Q"
				(at 10.16 3.81 0)
				(effects
					(font
						(size 1.27 1.27)
						(thickness 0.15)
					)
					(justify left bottom)
				)
			)
			(property "Value" "DMG1012T-7"
				(at 10.16 -3.81 0)
				(effects
					(font
						(size 1.27 1.27)
						(thickness 0.15)
					)
					(justify left bottom)
					(hide yes)
				)
			)
			(property "Footprint" "antmicro-footprints:SOT-523"
				(at 10.16 -6.35 0)
				(effects
					(font
						(size 1.27 1.27)
						(thickness 0.15)
					)
					(justify left bottom)
					(hide yes)
				)
			)
			(property "Datasheet" "https://www.diodes.com/assets/Datasheets/ds31783.pdf"
				(at 10.16 -8.89 0)
				(effects
					(font
						(size 1.27 1.27)
						(thickness 0.15)
					)
					(justify left bottom)
					(hide yes)
				)
			)
			(property "Description" "Power MOSFET, N Channel, 20 V, 630 mA, 0.3 ohm, SOT-523, Surface Mount"
				(at 47.752 -15.494 0)
				(effects
					(font
						(size 1.27 1.27)
					)
					(hide yes)
				)
			)
			(property "MPN" "DMG1012T-7"
				(at 10.16 1.27 0)
				(effects
					(font
						(size 1.27 1.27)
						(thickness 0.15)
					)
					(justify left bottom)
				)
			)
			(property "Manufacturer" "Diodes Incorporated"
				(at 10.16 -1.27 0)
				(effects
					(font
						(size 1.27 1.27)
						(thickness 0.15)
					)
					(justify left bottom)
					(hide yes)
				)
			)
			(property "Author" "Antmicro"
				(at 10.16 -11.43 0)
				(effects
					(font
						(size 1.27 1.27)
						(thickness 0.15)
					)
					(justify left bottom)
					(hide yes)
				)
			)
			(property "License" "Apache-2.0"
				(at 10.16 -13.97 0)
				(effects
					(font
						(size 1.27 1.27)
						(thickness 0.15)
					)
					(justify left bottom)
					(hide yes)
				)
			)
			(property "ki_keywords" "SMT, MOSFET, SEMICONDUCTOR"
				(at 0 0 0)
				(effects
					(font
						(size 1.27 1.27)
					)
					(hide yes)
				)
			)
			(symbol "DMG1012T-7_1_1"
				(polyline
					(pts
						(xy 1.27 0) (xy 3.302 0) (xy 3.302 3.937)
					)
					(stroke
						(width 0.254)
						(type default)
					)
					(fill
						(type none)
					)
				)
				(polyline
					(pts
						(xy 3.81 4.445) (xy 3.81 3.429)
					)
					(stroke
						(width 0.254)
						(type default)
					)
					(fill
						(type background)
					)
				)
				(polyline
					(pts
						(xy 3.81 2.54) (xy 3.81 3.048)
					)
					(stroke
						(width 0.254)
						(type default)
					)
					(fill
						(type background)
					)
				)
				(polyline
					(pts
						(xy 3.81 2.54) (xy 3.81 2.032)
					)
					(stroke
						(width 0.254)
						(type default)
					)
					(fill
						(type background)
					)
				)
				(polyline
					(pts
						(xy 3.81 2.54) (xy 4.572 3.048) (xy 4.572 2.032) (xy 3.81 2.54)
					)
					(stroke
						(width 0.254)
						(type default)
					)
					(fill
						(type outline)
					)
				)
				(polyline
					(pts
						(xy 3.81 1.143) (xy 3.81 1.651)
					)
					(stroke
						(width 0.254)
						(type default)
					)
					(fill
						(type background)
					)
				)
				(polyline
					(pts
						(xy 3.81 1.143) (xy 3.81 0.635)
					)
					(stroke
						(width 0.254)
						(type default)
					)
					(fill
						(type background)
					)
				)
				(circle
					(center 5.08 2.54)
					(radius 3.302)
					(stroke
						(width 0.254)
						(type default)
					)
					(fill
						(type background)
					)
				)
				(polyline
					(pts
						(xy 6.223 0.635) (xy 7.366 0.635) (xy 7.366 3.937) (xy 7.366 4.445) (xy 6.223 4.445)
					)
					(stroke
						(width 0.254)
						(type default)
					)
					(fill
						(type none)
					)
				)
				(polyline
					(pts
						(xy 6.35 6.35) (xy 6.35 3.937) (xy 3.81 3.937)
					)
					(stroke
						(width 0.254)
						(type default)
					)
					(fill
						(type none)
					)
				)
				(circle
					(center 6.35 4.445)
					(radius 0.127)
					(stroke
						(width 0.254)
						(type default)
					)
					(fill
						(type background)
					)
				)
				(polyline
					(pts
						(xy 6.35 1.143) (xy 3.81 1.143)
					)
					(stroke
						(width 0.254)
						(type default)
					)
					(fill
						(type background)
					)
				)
				(circle
					(center 6.35 1.143)
					(radius 0.127)
					(stroke
						(width 0.254)
						(type default)
					)
					(fill
						(type background)
					)
				)
				(circle
					(center 6.35 0.635)
					(radius 0.127)
					(stroke
						(width 0.254)
						(type default)
					)
					(fill
						(type background)
					)
				)
				(polyline
					(pts
						(xy 6.35 -1.27) (xy 6.35 2.54) (xy 3.81 2.54)
					)
					(stroke
						(width 0.254)
						(type default)
					)
					(fill
						(type none)
					)
				)
				(polyline
					(pts
						(xy 7.366 3.048) (xy 6.858 2.286) (xy 7.874 2.286) (xy 7.366 3.048)
					)
					(stroke
						(width 0.254)
						(type default)
					)
					(fill
						(type outline)
					)
				)
				(polyline
					(pts
						(xy 7.874 3.048) (xy 6.858 3.048)
					)
					(stroke
						(width 0.254)
						(type default)
					)
					(fill
						(type background)
					)
				)
				(pin input line
					(at 0 0 0)
					(length 2.54)
					(name "G"
						(effects
							(font
								(size 1.27 1.27)
							)
						)
					)
					(number "1"
						(effects
							(font
								(size 1.27 1.27)
							)
						)
					)
				)
				(pin passive line
					(at 6.35 7.62 270)
					(length 2.54)
					(name "D"
						(effects
							(font
								(size 1.27 1.27)
							)
						)
					)
					(number "3"
						(effects
							(font
								(size 1.27 1.27)
							)
						)
					)
				)
				(pin passive line
					(at 6.35 -2.54 90)
					(length 2.54)
					(name "S"
						(effects
							(font
								(size 1.27 1.27)
							)
						)
					)
					(number "2"
						(effects
							(font
								(size 1.27 1.27)
							)
						)
					)
				)
			)
		)
	(symbol "antmicroTransistorsFETsMOSFETsSingle:SQS401EN-T1_BE3"
			(pin_names
				(offset 0)
			)
			(exclude_from_sim no)
			(in_bom no)
			(on_board yes)
			(property "Reference" "Q"
				(at 15.24 -5.08 0)
				(effects
					(font
						(size 1.27 1.27)
						(thickness 0.15)
					)
					(justify left bottom)
				)
			)
			(property "Value" "SQS401EN-T1_BE3"
				(at 15.24 -10.16 0)
				(effects
					(font
						(size 1.27 1.27)
						(thickness 0.15)
					)
					(justify left bottom)
					(hide yes)
				)
			)
			(property "Footprint" "antmicro-footprints:Vishay_PowerPAK_1212-8_Single"
				(at 15.24 -12.7 0)
				(effects
					(font
						(size 1.27 1.27)
						(thickness 0.15)
					)
					(justify left bottom)
					(hide yes)
				)
			)
			(property "Datasheet" "https://www.vishay.com/docs/65529/sqs401en.pdf"
				(at 15.24 -15.24 0)
				(effects
					(font
						(size 1.27 1.27)
						(thickness 0.15)
					)
					(justify left bottom)
					(hide yes)
				)
			)
			(property "Description" "MOSFET, P Channel, 40 V, 16A, 0.047 ohm, PowerPAK 1212-8, Surface Mount"
				(at 53.34 -24.384 0)
				(effects
					(font
						(size 1.27 1.27)
					)
					(hide yes)
				)
			)
			(property "MPN" "SQS401EN-T1_BE3"
				(at 15.24 -7.62 0)
				(effects
					(font
						(size 1.27 1.27)
						(thickness 0.15)
					)
					(justify left bottom)
				)
			)
			(property "Manufacturer" "Vishay"
				(at 15.24 -17.78 0)
				(effects
					(font
						(size 1.27 1.27)
						(thickness 0.15)
					)
					(justify left bottom)
					(hide yes)
				)
			)
			(property "Author" "Antmicro"
				(at 15.24 -20.32 0)
				(effects
					(font
						(size 1.27 1.27)
						(thickness 0.15)
					)
					(justify left bottom)
					(hide yes)
				)
			)
			(property "License" "Apache-2.0"
				(at 15.24 -22.86 0)
				(effects
					(font
						(size 1.27 1.27)
						(thickness 0.15)
					)
					(justify left bottom)
					(hide yes)
				)
			)
			(property "ki_keywords" "SMT, TRANSISTOR, SEMICONDUCTOR, MOSFET, PMOS"
				(at 0 0 0)
				(effects
					(font
						(size 1.27 1.27)
					)
					(hide yes)
				)
			)
			(symbol "SQS401EN-T1_BE3_1_1"
				(polyline
					(pts
						(xy 1.27 0) (xy 3.302 0) (xy 3.302 3.937)
					)
					(stroke
						(width 0.254)
						(type default)
					)
					(fill
						(type none)
					)
				)
				(polyline
					(pts
						(xy 3.81 4.445) (xy 3.81 3.429)
					)
					(stroke
						(width 0.254)
						(type default)
					)
					(fill
						(type background)
					)
				)
				(polyline
					(pts
						(xy 3.81 2.54) (xy 3.81 3.048)
					)
					(stroke
						(width 0.254)
						(type default)
					)
					(fill
						(type background)
					)
				)
				(polyline
					(pts
						(xy 3.81 2.54) (xy 3.81 2.032)
					)
					(stroke
						(width 0.254)
						(type default)
					)
					(fill
						(type background)
					)
				)
				(polyline
					(pts
						(xy 3.81 1.143) (xy 3.81 1.651)
					)
					(stroke
						(width 0.254)
						(type default)
					)
					(fill
						(type background)
					)
				)
				(polyline
					(pts
						(xy 3.81 1.143) (xy 3.81 0.635)
					)
					(stroke
						(width 0.254)
						(type default)
					)
					(fill
						(type background)
					)
				)
				(circle
					(center 5.08 2.54)
					(radius 3.302)
					(stroke
						(width 0.254)
						(type default)
					)
					(fill
						(type background)
					)
				)
				(polyline
					(pts
						(xy 6.096 2.54) (xy 5.334 2.032) (xy 5.334 3.048) (xy 6.096 2.54)
					)
					(stroke
						(width 0.254)
						(type default)
					)
					(fill
						(type outline)
					)
				)
				(polyline
					(pts
						(xy 6.223 0.635) (xy 7.366 0.635) (xy 7.366 3.937) (xy 7.366 4.445) (xy 6.223 4.445)
					)
					(stroke
						(width 0.254)
						(type default)
					)
					(fill
						(type none)
					)
				)
				(polyline
					(pts
						(xy 6.35 6.35) (xy 6.35 3.937) (xy 3.81 3.937)
					)
					(stroke
						(width 0.254)
						(type default)
					)
					(fill
						(type none)
					)
				)
				(circle
					(center 6.35 4.445)
					(radius 0.127)
					(stroke
						(width 0.254)
						(type default)
					)
					(fill
						(type background)
					)
				)
				(polyline
					(pts
						(xy 6.35 1.143) (xy 3.81 1.143)
					)
					(stroke
						(width 0.254)
						(type default)
					)
					(fill
						(type background)
					)
				)
				(circle
					(center 6.35 1.143)
					(radius 0.127)
					(stroke
						(width 0.254)
						(type default)
					)
					(fill
						(type background)
					)
				)
				(circle
					(center 6.35 0.635)
					(radius 0.127)
					(stroke
						(width 0.254)
						(type default)
					)
					(fill
						(type background)
					)
				)
				(polyline
					(pts
						(xy 6.35 -1.27) (xy 6.35 2.54) (xy 3.81 2.54)
					)
					(stroke
						(width 0.254)
						(type default)
					)
					(fill
						(type none)
					)
				)
				(polyline
					(pts
						(xy 7.366 2.286) (xy 7.874 3.048) (xy 6.858 3.048) (xy 7.366 2.286)
					)
					(stroke
						(width 0.254)
						(type default)
					)
					(fill
						(type outline)
					)
				)
				(polyline
					(pts
						(xy 7.874 2.286) (xy 6.858 2.286)
					)
					(stroke
						(width 0.254)
						(type default)
					)
					(fill
						(type background)
					)
				)
				(pin input line
					(at 0 0 0)
					(length 2.54)
					(name "G"
						(effects
							(font
								(size 1.27 1.27)
							)
						)
					)
					(number "4"
						(effects
							(font
								(size 1.27 1.27)
							)
						)
					)
				)
				(pin passive line
					(at 6.35 7.62 270)
					(length 2.54)
					(name "D"
						(effects
							(font
								(size 1.27 1.27)
							)
						)
					)
					(number "5"
						(effects
							(font
								(size 1.27 1.27)
							)
						)
					)
				)
				(pin passive line
					(at 6.35 -2.54 90)
					(length 2.54)
					(name "S"
						(effects
							(font
								(size 1.27 1.27)
							)
						)
					)
					(number "1"
						(effects
							(font
								(size 1.27 1.27)
							)
						)
					)
				)
				(pin passive line
					(at 6.35 -2.54 90)
					(length 2.54)
					(hide yes)
					(name "S"
						(effects
							(font
								(size 1.27 1.27)
							)
						)
					)
					(number "2"
						(effects
							(font
								(size 1.27 1.27)
							)
						)
					)
				)
				(pin passive line
					(at 6.35 -2.54 90)
					(length 2.54)
					(hide yes)
					(name "S"
						(effects
							(font
								(size 1.27 1.27)
							)
						)
					)
					(number "3"
						(effects
							(font
								(size 1.27 1.27)
							)
						)
					)
				)
			)
		)
	(symbol "antmicroWire2BoardConnectors:Molex_Nano-Fit_1x2_SMD_1054301202"
			(exclude_from_sim no)
			(in_bom yes)
			(on_board yes)
			(property "Reference" "J"
				(at 26.67 -2.54 0)
				(effects
					(font
						(size 1.27 1.27)
						(thickness 0.15)
					)
					(justify left bottom)
				)
			)
			(property "Value" "Molex_Nano-Fit_1x2_SMD_1054301202"
				(at 26.67 -7.62 0)
				(effects
					(font
						(size 1.27 1.27)
						(thickness 0.15)
					)
					(justify left bottom)
					(hide yes)
				)
			)
			(property "Footprint" "antmicro-footprints:Conn_Molex_Nano-Fit_1x2_SMD_1054301202"
				(at 26.67 -10.16 0)
				(effects
					(font
						(size 1.27 1.27)
						(thickness 0.15)
					)
					(justify left bottom)
					(hide yes)
				)
			)
			(property "Datasheet" "https://www.farnell.com/cad/3578051.pdf"
				(at 26.67 -12.7 0)
				(effects
					(font
						(size 1.27 1.27)
						(thickness 0.15)
					)
					(justify left bottom)
					(hide yes)
				)
			)
			(property "Description" "Pin Header, Pitch 2.5 mm, 1 Row, 2 Contacts, Nano-Fit"
				(at 0 0 0)
				(effects
					(font
						(size 1.27 1.27)
					)
					(hide yes)
				)
			)
			(property "Manufacturer" "Molex"
				(at 26.67 -15.24 0)
				(effects
					(font
						(size 1.27 1.27)
						(thickness 0.15)
					)
					(justify left bottom)
					(hide yes)
				)
			)
			(property "MPN" "105430-1202"
				(at 26.67 -5.08 0)
				(effects
					(font
						(size 1.27 1.27)
						(thickness 0.15)
					)
					(justify left bottom)
				)
			)
			(property "Author" "Antmicro"
				(at 26.67 -17.78 0)
				(effects
					(font
						(size 1.27 1.27)
						(thickness 0.15)
					)
					(justify left bottom)
					(hide yes)
				)
			)
			(property "License" "Apache-2.0"
				(at 26.67 -20.32 0)
				(effects
					(font
						(size 1.27 1.27)
						(thickness 0.15)
					)
					(justify left bottom)
					(hide yes)
				)
			)
			(property "ki_keywords" "CONNECTOR, HEADER, HORIZONTAL, SMT"
				(at 0 0 0)
				(effects
					(font
						(size 1.27 1.27)
					)
					(hide yes)
				)
			)
			(symbol "Molex_Nano-Fit_1x2_SMD_1054301202_1_1"
				(rectangle
					(start 2.54 2.54)
					(end 6.35 -7.62)
					(stroke
						(width 0.254)
						(type default)
					)
					(fill
						(type background)
					)
				)
				(rectangle
					(start 2.54 -0.254)
					(end 4.1402 0.381)
					(stroke
						(width 0.254)
						(type default)
					)
					(fill
						(type background)
					)
				)
				(rectangle
					(start 2.54 -2.794)
					(end 4.1402 -2.159)
					(stroke
						(width 0.254)
						(type default)
					)
					(fill
						(type background)
					)
				)
				(rectangle
					(start 2.54 -5.334)
					(end 4.1402 -4.699)
					(stroke
						(width 0.254)
						(type default)
					)
					(fill
						(type background)
					)
				)
				(pin passive line
					(at 0 0 0)
					(length 2.54)
					(name "~"
						(effects
							(font
								(size 1.27 1.27)
							)
						)
					)
					(number "1"
						(effects
							(font
								(size 1.27 1.27)
							)
						)
					)
				)
				(pin passive line
					(at 0 -2.54 0)
					(length 2.54)
					(name "~"
						(effects
							(font
								(size 1.27 1.27)
							)
						)
					)
					(number "2"
						(effects
							(font
								(size 1.27 1.27)
							)
						)
					)
				)
				(pin passive line
					(at 0 -5.08 0)
					(length 2.54)
					(name "~"
						(effects
							(font
								(size 1.27 1.27)
							)
						)
					)
					(number "MP"
						(effects
							(font
								(size 1.27 1.27)
							)
						)
					)
				)
			)
		)
	(symbol "antmicropower:+12V"
			(power)
			(pin_names
				(offset 0)
			)
			(exclude_from_sim no)
			(in_bom yes)
			(on_board yes)
			(property "Reference" "#PWR"
				(at 0 -3.81 0)
				(effects
					(font
						(size 1.27 1.27)
					)
					(hide yes)
				)
			)
			(property "Value" "+12V"
				(at 0 3.556 0)
				(effects
					(font
						(size 1.27 1.27)
					)
				)
			)
			(property "Footprint" ""
				(at 0 0 0)
				(effects
					(font
						(size 1.27 1.27)
					)
					(hide yes)
				)
			)
			(property "Datasheet" ""
				(at 0 0 0)
				(effects
					(font
						(size 1.27 1.27)
					)
					(hide yes)
				)
			)
			(property "Description" ""
				(at 0 0 0)
				(effects
					(font
						(size 1.27 1.27)
					)
					(hide yes)
				)
			)
			(symbol "+12V_0_1"
				(polyline
					(pts
						(xy -0.762 1.27) (xy 0 2.54)
					)
					(stroke
						(width 0)
						(type default)
					)
					(fill
						(type none)
					)
				)
				(polyline
					(pts
						(xy 0 2.54) (xy 0.762 1.27)
					)
					(stroke
						(width 0)
						(type default)
					)
					(fill
						(type none)
					)
				)
				(polyline
					(pts
						(xy 0 0) (xy 0 2.54)
					)
					(stroke
						(width 0)
						(type default)
					)
					(fill
						(type none)
					)
				)
			)
			(symbol "+12V_1_1"
				(pin power_in line
					(at 0 0 90)
					(length 0)
					(hide yes)
					(name "+12V"
						(effects
							(font
								(size 1.27 1.27)
							)
						)
					)
					(number "1"
						(effects
							(font
								(size 1.27 1.27)
							)
						)
					)
				)
			)
		)
	(symbol "antmicropower:+1V2"
			(power)
			(pin_names
				(offset 0)
			)
			(exclude_from_sim no)
			(in_bom yes)
			(on_board yes)
			(property "Reference" "#PWR"
				(at 0 -3.81 0)
				(effects
					(font
						(size 1.27 1.27)
					)
					(hide yes)
				)
			)
			(property "Value" "+1V2"
				(at 0 3.556 0)
				(effects
					(font
						(size 1.27 1.27)
					)
				)
			)
			(property "Footprint" ""
				(at 0 0 0)
				(effects
					(font
						(size 1.27 1.27)
					)
					(hide yes)
				)
			)
			(property "Datasheet" ""
				(at 0 0 0)
				(effects
					(font
						(size 1.27 1.27)
					)
					(hide yes)
				)
			)
			(property "Description" ""
				(at 0 0 0)
				(effects
					(font
						(size 1.27 1.27)
					)
					(hide yes)
				)
			)
			(symbol "+1V2_0_1"
				(polyline
					(pts
						(xy -0.762 1.27) (xy 0 2.54)
					)
					(stroke
						(width 0)
						(type default)
					)
					(fill
						(type none)
					)
				)
				(polyline
					(pts
						(xy 0 2.54) (xy 0.762 1.27)
					)
					(stroke
						(width 0)
						(type default)
					)
					(fill
						(type none)
					)
				)
				(polyline
					(pts
						(xy 0 0) (xy 0 2.54)
					)
					(stroke
						(width 0)
						(type default)
					)
					(fill
						(type none)
					)
				)
			)
			(symbol "+1V2_1_1"
				(pin power_in line
					(at 0 0 90)
					(length 0)
					(hide yes)
					(name "+1V2"
						(effects
							(font
								(size 1.27 1.27)
							)
						)
					)
					(number "1"
						(effects
							(font
								(size 1.27 1.27)
							)
						)
					)
				)
			)
		)
	(symbol "antmicropower:+1V8"
			(power)
			(pin_numbers
				(hide yes)
			)
			(pin_names
				(hide yes)
			)
			(exclude_from_sim no)
			(in_bom yes)
			(on_board yes)
			(property "Reference" "#PWR"
				(at 15.24 -2.54 0)
				(effects
					(font
						(size 1.27 1.27)
						(thickness 0.15)
					)
					(justify left bottom)
					(hide yes)
				)
			)
			(property "Value" "+1V8"
				(at -3.175 2.54 0)
				(effects
					(font
						(size 1.27 1.27)
						(thickness 0.15)
					)
					(justify left bottom)
				)
			)
			(property "Footprint" ""
				(at 15.24 -7.62 0)
				(effects
					(font
						(size 1.27 1.27)
						(thickness 0.15)
					)
					(justify left bottom)
					(hide yes)
				)
			)
			(property "Datasheet" ""
				(at 15.24 -10.16 0)
				(effects
					(font
						(size 1.27 1.27)
						(thickness 0.15)
					)
					(justify left bottom)
					(hide yes)
				)
			)
			(property "Description" ""
				(at 0 0 0)
				(effects
					(font
						(size 1.27 1.27)
					)
					(hide yes)
				)
			)
			(property "Author" "Antmicro"
				(at 15.24 -5.08 0)
				(effects
					(font
						(size 1.27 1.27)
						(thickness 0.15)
					)
					(justify left bottom)
					(hide yes)
				)
			)
			(property "License" "Apache-2.0"
				(at 15.24 -7.62 0)
				(effects
					(font
						(size 1.27 1.27)
						(thickness 0.15)
					)
					(justify left bottom)
					(hide yes)
				)
			)
			(symbol "+1V8_1_1"
				(polyline
					(pts
						(xy -0.762 1.27) (xy 0 2.54)
					)
					(stroke
						(width 0)
						(type default)
					)
					(fill
						(type background)
					)
				)
				(polyline
					(pts
						(xy 0 2.54) (xy 0.762 1.27)
					)
					(stroke
						(width 0)
						(type default)
					)
					(fill
						(type background)
					)
				)
				(polyline
					(pts
						(xy 0 0) (xy 0 2.54)
					)
					(stroke
						(width 0)
						(type default)
					)
					(fill
						(type background)
					)
				)
				(pin power_in line
					(at 0 0 90)
					(length 0)
					(hide yes)
					(name "+1V8"
						(effects
							(font
								(size 1.27 1.27)
							)
						)
					)
					(number "1"
						(effects
							(font
								(size 1.27 1.27)
							)
						)
					)
				)
			)
		)
	(symbol "antmicropower:+5V"
			(power)
			(pin_numbers
				(hide yes)
			)
			(pin_names
				(hide yes)
			)
			(exclude_from_sim no)
			(in_bom yes)
			(on_board yes)
			(property "Reference" "#PWR"
				(at 15.24 -2.54 0)
				(effects
					(font
						(size 1.27 1.27)
						(thickness 0.15)
					)
					(justify left bottom)
					(hide yes)
				)
			)
			(property "Value" "+5V"
				(at 15.24 -5.08 0)
				(effects
					(font
						(size 1.27 1.27)
						(thickness 0.15)
					)
					(justify left bottom)
				)
			)
			(property "Footprint" ""
				(at 15.24 -7.62 0)
				(effects
					(font
						(size 1.27 1.27)
						(thickness 0.15)
					)
					(justify left bottom)
					(hide yes)
				)
			)
			(property "Datasheet" ""
				(at 15.24 -10.16 0)
				(effects
					(font
						(size 1.27 1.27)
						(thickness 0.15)
					)
					(justify left bottom)
					(hide yes)
				)
			)
			(property "Description" ""
				(at 0 0 0)
				(effects
					(font
						(size 1.27 1.27)
					)
					(hide yes)
				)
			)
			(property "Author" "Antmicro"
				(at 15.24 -7.62 0)
				(effects
					(font
						(size 1.27 1.27)
						(thickness 0.15)
					)
					(justify left bottom)
					(hide yes)
				)
			)
			(property "License" "Apache-2.0"
				(at 15.24 -10.16 0)
				(effects
					(font
						(size 1.27 1.27)
						(thickness 0.15)
					)
					(justify left bottom)
					(hide yes)
				)
			)
			(symbol "+5V_1_1"
				(polyline
					(pts
						(xy -0.762 1.27) (xy 0 2.54)
					)
					(stroke
						(width 0)
						(type default)
					)
					(fill
						(type background)
					)
				)
				(polyline
					(pts
						(xy 0 2.54) (xy 0.762 1.27)
					)
					(stroke
						(width 0)
						(type default)
					)
					(fill
						(type background)
					)
				)
				(polyline
					(pts
						(xy 0 0) (xy 0 2.54)
					)
					(stroke
						(width 0)
						(type default)
					)
					(fill
						(type background)
					)
				)
				(pin power_in line
					(at 0 0 90)
					(length 0)
					(name "+5V"
						(effects
							(font
								(size 1.27 1.27)
							)
						)
					)
					(number "1"
						(effects
							(font
								(size 1.27 1.27)
							)
						)
					)
				)
			)
		)
	(symbol "antmicropower:GND"
			(power)
			(pin_numbers
				(hide yes)
			)
			(pin_names
				(hide yes)
			)
			(exclude_from_sim no)
			(in_bom yes)
			(on_board yes)
			(property "Reference" "#PWR"
				(at 8.89 -2.54 0)
				(effects
					(font
						(size 1.27 1.27)
						(thickness 0.15)
					)
					(justify left bottom)
					(hide yes)
				)
			)
			(property "Value" "GND"
				(at 8.89 -5.08 0)
				(effects
					(font
						(size 1.27 1.27)
						(thickness 0.15)
					)
					(justify left bottom)
				)
			)
			(property "Footprint" ""
				(at 8.89 -7.62 0)
				(effects
					(font
						(size 1.27 1.27)
						(thickness 0.15)
					)
					(justify left bottom)
					(hide yes)
				)
			)
			(property "Datasheet" ""
				(at 8.89 -12.7 0)
				(effects
					(font
						(size 1.27 1.27)
						(thickness 0.15)
					)
					(justify left bottom)
					(hide yes)
				)
			)
			(property "Description" ""
				(at 0 0 0)
				(effects
					(font
						(size 1.27 1.27)
					)
					(hide yes)
				)
			)
			(property "Author" "Antmicro"
				(at 8.89 -7.62 0)
				(effects
					(font
						(size 1.27 1.27)
						(thickness 0.15)
					)
					(justify left bottom)
					(hide yes)
				)
			)
			(property "License" "Apache-2.0"
				(at 8.89 -10.16 0)
				(effects
					(font
						(size 1.27 1.27)
						(thickness 0.15)
					)
					(justify left bottom)
					(hide yes)
				)
			)
			(symbol "GND_1_1"
				(polyline
					(pts
						(xy 0 0) (xy 0 -1.27) (xy 1.27 -1.27) (xy 0 -2.54) (xy -1.27 -1.27) (xy 0 -1.27)
					)
					(stroke
						(width 0)
						(type default)
					)
					(fill
						(type none)
					)
				)
				(pin power_in line
					(at 0 0 270)
					(length 0)
					(name "GND"
						(effects
							(font
								(size 1.27 1.27)
							)
						)
					)
					(number "1"
						(effects
							(font
								(size 1.27 1.27)
							)
						)
					)
				)
			)
		)
	(symbol "antmicropower:PWR_FLAG"
			(power)
			(pin_numbers
				(hide yes)
			)
			(pin_names
				(offset 0)
				(hide yes)
			)
			(exclude_from_sim no)
			(in_bom yes)
			(on_board yes)
			(property "Reference" "#FLG"
				(at 0 1.905 0)
				(effects
					(font
						(size 1.27 1.27)
					)
					(hide yes)
				)
			)
			(property "Value" "PWR_FLAG"
				(at 0 3.81 0)
				(effects
					(font
						(size 1.27 1.27)
					)
				)
			)
			(property "Footprint" ""
				(at 0 0 0)
				(effects
					(font
						(size 1.27 1.27)
					)
					(hide yes)
				)
			)
			(property "Datasheet" ""
				(at 0 0 0)
				(effects
					(font
						(size 1.27 1.27)
					)
					(hide yes)
				)
			)
			(property "Description" ""
				(at 0 0 0)
				(effects
					(font
						(size 1.27 1.27)
					)
					(hide yes)
				)
			)
			(symbol "PWR_FLAG_0_0"
				(pin power_out line
					(at 0 0 90)
					(length 0)
					(name "pwr"
						(effects
							(font
								(size 1.27 1.27)
							)
						)
					)
					(number "1"
						(effects
							(font
								(size 1.27 1.27)
							)
						)
					)
				)
			)
			(symbol "PWR_FLAG_0_1"
				(polyline
					(pts
						(xy 0 0) (xy 0 1.27) (xy -1.016 1.905) (xy 0 2.54) (xy 1.016 1.905) (xy 0 1.27)
					)
					(stroke
						(width 0)
						(type default)
					)
					(fill
						(type none)
					)
				)
			)
		)
)
